G04 ================== begin FILE IDENTIFICATION RECORD ==================*
G04 Layout Name:  13130-1b.brd*
G04 Film Name:    L6VCC*
G04 File Format:  Gerber RS274X*
G04 File Origin:  Cadence Allegro 16.5-S037*
G04 Origin Date:  Thu Nov 13 17:27:03 2014*
G04 *
G04 Layer:  VIA CLASS/L6VCC*
G04 Layer:  PIN/L6VCC*
G04 Layer:  PACKAGE GEOMETRY/PWRVCC*
G04 Layer:  ETCH/L6VCC*
G04 Layer:  DRAWING FORMAT/LAYER_PCB_STORY*
G04 Layer:  DRAWING FORMAT/LAYER_L6VCC*
G04 *
G04 Offset:    (0.00 0.00)*
G04 Mirror:    No*
G04 Mode:      Negative*
G04 Rotation:  0*
G04 FullContactRelief:  No*
G04 UndefLineWidth:     6.00*
G04 ================== end FILE IDENTIFICATION RECORD ====================*
%FSLAX35Y35*MOIN*%
%IR0*IPPOS*OFA0.00000B0.00000*MIA0B0*SFA1.00000B1.00000*%
%ADD15C,.03*%
%ADD20C,.032*%
%ADD18C,.072*%
%ADD12C,.036*%
%ADD24C,.028*%
%ADD22C,.091*%
%ADD17C,.093*%
%ADD19C,.068*%
%AMMACRO23*
4,1,15,.00398,.00044,
.003999,.000208,
.004004,-.000025,
.003996,-.000258,
.00398,-.00044,
.00483,-.00129,
.004897,-.001007,
.004947,-.000721,
.004981,-.000432,
.004997,-.000141,
.004997,.000149,
.00498,.00044,
.004946,.000729,
.004895,.001015,
.00483,.00129,
.00398,.00044,
45.*
4,1,15,.00044,-.00398,
.000208,-.003999,
-.000025,-.004004,
-.000258,-.003996,
-.00044,-.00398,
-.00129,-.00483,
-.001007,-.004897,
-.000721,-.004947,
-.000432,-.004981,
-.000141,-.004997,
.000149,-.004997,
.00044,-.00498,
.000729,-.004946,
.001015,-.004895,
.00129,-.00483,
.00044,-.00398,
45.*
4,1,15,-.00398,-.00044,
-.003999,-.000208,
-.004004,.000025,
-.003996,.000258,
-.00398,.00044,
-.00483,.00129,
-.004897,.001007,
-.004947,.000721,
-.004981,.000432,
-.004997,.000141,
-.004997,-.000149,
-.00498,-.00044,
-.004946,-.000729,
-.004895,-.001015,
-.00483,-.00129,
-.00398,-.00044,
45.*
4,1,15,-.00044,.00398,
-.000208,.003999,
.000025,.004004,
.000258,.003996,
.00044,.00398,
.00129,.00483,
.001007,.004897,
.000721,.004947,
.000432,.004981,
.000141,.004997,
-.000149,.004997,
-.00044,.00498,
-.000729,.004946,
-.001015,.004895,
-.00129,.00483,
-.00044,.00398,
45.*
%
%ADD23MACRO23*%
%AMMACRO13*
4,1,15,.00398,.00044,
.003999,.000208,
.004004,-.000025,
.003996,-.000258,
.00398,-.00044,
.00483,-.00129,
.004897,-.001007,
.004947,-.000721,
.004981,-.000432,
.004997,-.000141,
.004997,.000149,
.00498,.00044,
.004946,.000729,
.004895,.001015,
.00483,.00129,
.00398,.00044,
90.*
4,1,15,.00044,-.00398,
.000208,-.003999,
-.000025,-.004004,
-.000258,-.003996,
-.00044,-.00398,
-.00129,-.00483,
-.001007,-.004897,
-.000721,-.004947,
-.000432,-.004981,
-.000141,-.004997,
.000149,-.004997,
.00044,-.00498,
.000729,-.004946,
.001015,-.004895,
.00129,-.00483,
.00044,-.00398,
90.*
4,1,15,-.00398,-.00044,
-.003999,-.000208,
-.004004,.000025,
-.003996,.000258,
-.00398,.00044,
-.00483,.00129,
-.004897,.001007,
-.004947,.000721,
-.004981,.000432,
-.004997,.000141,
-.004997,-.000149,
-.00498,-.00044,
-.004946,-.000729,
-.004895,-.001015,
-.00483,-.00129,
-.00398,-.00044,
90.*
4,1,15,-.00044,.00398,
-.000208,.003999,
.000025,.004004,
.000258,.003996,
.00044,.00398,
.00129,.00483,
.001007,.004897,
.000721,.004947,
.000432,.004981,
.000141,.004997,
-.000149,.004997,
-.00044,.00498,
-.000729,.004946,
-.001015,.004895,
-.00129,.00483,
-.00044,.00398,
90.*
%
%ADD13MACRO13*%
%AMMACRO14*
4,1,15,.00398,.00044,
.003999,.000208,
.004004,-.000025,
.003996,-.000258,
.00398,-.00044,
.00483,-.00129,
.004897,-.001007,
.004947,-.000721,
.004981,-.000432,
.004997,-.000141,
.004997,.000149,
.00498,.00044,
.004946,.000729,
.004895,.001015,
.00483,.00129,
.00398,.00044,
0.0*
4,1,15,.00044,-.00398,
.000208,-.003999,
-.000025,-.004004,
-.000258,-.003996,
-.00044,-.00398,
-.00129,-.00483,
-.001007,-.004897,
-.000721,-.004947,
-.000432,-.004981,
-.000141,-.004997,
.000149,-.004997,
.00044,-.00498,
.000729,-.004946,
.001015,-.004895,
.00129,-.00483,
.00044,-.00398,
0.0*
4,1,15,-.00398,-.00044,
-.003999,-.000208,
-.004004,.000025,
-.003996,.000258,
-.00398,.00044,
-.00483,.00129,
-.004897,.001007,
-.004947,.000721,
-.004981,.000432,
-.004997,.000141,
-.004997,-.000149,
-.00498,-.00044,
-.004946,-.000729,
-.004895,-.001015,
-.00483,-.00129,
-.00398,-.00044,
0.0*
4,1,15,-.00044,.00398,
-.000208,.003999,
.000025,.004004,
.000258,.003996,
.00044,.00398,
.00129,.00483,
.001007,.004897,
.000721,.004947,
.000432,.004981,
.000141,.004997,
-.000149,.004997,
-.00044,.00498,
-.000729,.004946,
-.001015,.004895,
-.00129,.00483,
-.00044,.00398,
0.0*
%
%ADD14MACRO14*%
%ADD29O,.217X.154*%
%ADD11C,.114*%
%ADD16C,.154*%
%ADD21C,.147*%
%ADD10C,.168*%
%AMMACRO30*
4,1,15,.00398,.00044,
.003999,.000208,
.004004,-.000025,
.003996,-.000258,
.00398,-.00044,
.00483,-.00129,
.004897,-.001007,
.004947,-.000721,
.004981,-.000432,
.004997,-.000141,
.004997,.000149,
.00498,.00044,
.004946,.000729,
.004895,.001015,
.00483,.00129,
.00398,.00044,
225.*
4,1,15,.00044,-.00398,
.000208,-.003999,
-.000025,-.004004,
-.000258,-.003996,
-.00044,-.00398,
-.00129,-.00483,
-.001007,-.004897,
-.000721,-.004947,
-.000432,-.004981,
-.000141,-.004997,
.000149,-.004997,
.00044,-.00498,
.000729,-.004946,
.001015,-.004895,
.00129,-.00483,
.00044,-.00398,
225.*
4,1,15,-.00398,-.00044,
-.003999,-.000208,
-.004004,.000025,
-.003996,.000258,
-.00398,.00044,
-.00483,.00129,
-.004897,.001007,
-.004947,.000721,
-.004981,.000432,
-.004997,.000141,
-.004997,-.000149,
-.00498,-.00044,
-.004946,-.000729,
-.004895,-.001015,
-.00483,-.00129,
-.00398,-.00044,
225.*
4,1,15,-.00044,.00398,
-.000208,.003999,
.000025,.004004,
.000258,.003996,
.00044,.00398,
.00129,.00483,
.001007,.004897,
.000721,.004947,
.000432,.004981,
.000141,.004997,
-.000149,.004997,
-.00044,.00498,
-.000729,.004946,
-.001015,.004895,
-.00129,.00483,
-.00044,.00398,
225.*
%
%ADD30MACRO30*%
%AMMACRO28*
4,1,15,.00398,.00044,
.003999,.000208,
.004004,-.000025,
.003996,-.000258,
.00398,-.00044,
.00483,-.00129,
.004897,-.001007,
.004947,-.000721,
.004981,-.000432,
.004997,-.000141,
.004997,.000149,
.00498,.00044,
.004946,.000729,
.004895,.001015,
.00483,.00129,
.00398,.00044,
315.*
4,1,15,.00044,-.00398,
.000208,-.003999,
-.000025,-.004004,
-.000258,-.003996,
-.00044,-.00398,
-.00129,-.00483,
-.001007,-.004897,
-.000721,-.004947,
-.000432,-.004981,
-.000141,-.004997,
.000149,-.004997,
.00044,-.00498,
.000729,-.004946,
.001015,-.004895,
.00129,-.00483,
.00044,-.00398,
315.*
4,1,15,-.00398,-.00044,
-.003999,-.000208,
-.004004,.000025,
-.003996,.000258,
-.00398,.00044,
-.00483,.00129,
-.004897,.001007,
-.004947,.000721,
-.004981,.000432,
-.004997,.000141,
-.004997,-.000149,
-.00498,-.00044,
-.004946,-.000729,
-.004895,-.001015,
-.00483,-.00129,
-.00398,-.00044,
315.*
4,1,15,-.00044,.00398,
-.000208,.003999,
.000025,.004004,
.000258,.003996,
.00044,.00398,
.00129,.00483,
.001007,.004897,
.000721,.004947,
.000432,.004981,
.000141,.004997,
-.000149,.004997,
-.00044,.00498,
-.000729,.004946,
-.001015,.004895,
-.00129,.00483,
-.00044,.00398,
315.*
%
%ADD28MACRO28*%
%AMMACRO27*
4,1,15,.00398,.00044,
.003999,.000208,
.004004,-.000025,
.003996,-.000258,
.00398,-.00044,
.00483,-.00129,
.004897,-.001007,
.004947,-.000721,
.004981,-.000432,
.004997,-.000141,
.004997,.000149,
.00498,.00044,
.004946,.000729,
.004895,.001015,
.00483,.00129,
.00398,.00044,
180.*
4,1,15,.00044,-.00398,
.000208,-.003999,
-.000025,-.004004,
-.000258,-.003996,
-.00044,-.00398,
-.00129,-.00483,
-.001007,-.004897,
-.000721,-.004947,
-.000432,-.004981,
-.000141,-.004997,
.000149,-.004997,
.00044,-.00498,
.000729,-.004946,
.001015,-.004895,
.00129,-.00483,
.00044,-.00398,
180.*
4,1,15,-.00398,-.00044,
-.003999,-.000208,
-.004004,.000025,
-.003996,.000258,
-.00398,.00044,
-.00483,.00129,
-.004897,.001007,
-.004947,.000721,
-.004981,.000432,
-.004997,.000141,
-.004997,-.000149,
-.00498,-.00044,
-.004946,-.000729,
-.004895,-.001015,
-.00483,-.00129,
-.00398,-.00044,
180.*
4,1,15,-.00044,.00398,
-.000208,.003999,
.000025,.004004,
.000258,.003996,
.00044,.00398,
.00129,.00483,
.001007,.004897,
.000721,.004947,
.000432,.004981,
.000141,.004997,
-.000149,.004997,
-.00044,.00498,
-.000729,.004946,
-.001015,.004895,
-.00129,.00483,
-.00044,.00398,
180.*
%
%ADD27MACRO27*%
%AMMACRO26*
4,1,15,.00398,.00044,
.003999,.000208,
.004004,-.000025,
.003996,-.000258,
.00398,-.00044,
.00483,-.00129,
.004897,-.001007,
.004947,-.000721,
.004981,-.000432,
.004997,-.000141,
.004997,.000149,
.00498,.00044,
.004946,.000729,
.004895,.001015,
.00483,.00129,
.00398,.00044,
270.*
4,1,15,.00044,-.00398,
.000208,-.003999,
-.000025,-.004004,
-.000258,-.003996,
-.00044,-.00398,
-.00129,-.00483,
-.001007,-.004897,
-.000721,-.004947,
-.000432,-.004981,
-.000141,-.004997,
.000149,-.004997,
.00044,-.00498,
.000729,-.004946,
.001015,-.004895,
.00129,-.00483,
.00044,-.00398,
270.*
4,1,15,-.00398,-.00044,
-.003999,-.000208,
-.004004,.000025,
-.003996,.000258,
-.00398,.00044,
-.00483,.00129,
-.004897,.001007,
-.004947,.000721,
-.004981,.000432,
-.004997,.000141,
-.004997,-.000149,
-.00498,-.00044,
-.004946,-.000729,
-.004895,-.001015,
-.00483,-.00129,
-.00398,-.00044,
270.*
4,1,15,-.00044,.00398,
-.000208,.003999,
.000025,.004004,
.000258,.003996,
.00044,.00398,
.00129,.00483,
.001007,.004897,
.000721,.004947,
.000432,.004981,
.000141,.004997,
-.000149,.004997,
-.00044,.00498,
-.000729,.004946,
-.001015,.004895,
-.00129,.00483,
-.00044,.00398,
270.*
%
%ADD26MACRO26*%
%AMMACRO25*
4,1,15,.00398,.00044,
.003999,.000208,
.004004,-.000025,
.003996,-.000258,
.00398,-.00044,
.00483,-.00129,
.004897,-.001007,
.004947,-.000721,
.004981,-.000432,
.004997,-.000141,
.004997,.000149,
.00498,.00044,
.004946,.000729,
.004895,.001015,
.00483,.00129,
.00398,.00044,
135.*
4,1,15,.00044,-.00398,
.000208,-.003999,
-.000025,-.004004,
-.000258,-.003996,
-.00044,-.00398,
-.00129,-.00483,
-.001007,-.004897,
-.000721,-.004947,
-.000432,-.004981,
-.000141,-.004997,
.000149,-.004997,
.00044,-.00498,
.000729,-.004946,
.001015,-.004895,
.00129,-.00483,
.00044,-.00398,
135.*
4,1,15,-.00398,-.00044,
-.003999,-.000208,
-.004004,.000025,
-.003996,.000258,
-.00398,.00044,
-.00483,.00129,
-.004897,.001007,
-.004947,.000721,
-.004981,.000432,
-.004997,.000141,
-.004997,-.000149,
-.00498,-.00044,
-.004946,-.000729,
-.004895,-.001015,
-.00483,-.00129,
-.00398,-.00044,
135.*
4,1,15,-.00044,.00398,
-.000208,.003999,
.000025,.004004,
.000258,.003996,
.00044,.00398,
.00129,.00483,
.001007,.004897,
.000721,.004947,
.000432,.004981,
.000141,.004997,
-.000149,.004997,
-.00044,.00498,
-.000729,.004946,
-.001015,.004895,
-.00129,.00483,
-.00044,.00398,
135.*
%
%ADD25MACRO25*%
%ADD31C,.02*%
%ADD32C,.006*%
%ADD39C,.03004*%
%ADD36C,.06804*%
%ADD37C,.08704*%
%ADD35C,.08904*%
%ADD38C,.09176*%
%ADD40O,.21302X.15002*%
%ADD34C,.11004*%
%ADD33C,.15004*%
G75*
%LPD*%
G75*
G36*
G01X-6000Y-6000D02*
X832773D01*
Y296551D01*
X-6000D01*
Y-6000D01*
G37*
%LPC*%
G75*
G36*
G01X3937Y60878D02*
G02X3004Y61811I0J933D01*
G01Y129750D01*
X21689D01*
X23750Y127689D01*
Y121105D01*
X23737Y121071D01*
G03Y119529I2063J-771D01*
G01X23750Y119495D01*
Y93689D01*
X27189Y90250D01*
X33311D01*
X35811Y92750D01*
X62689D01*
X84189Y71250D01*
X141970D01*
G02X142196Y70520I0J-400D01*
G03X145804I1804J-2645D01*
G02X146030Y71250I226J330D01*
G01X241689D01*
X242689Y70250D01*
X283811D01*
X285811Y72250D01*
X316811D01*
X317811Y73250D01*
X329689D01*
X331689Y71250D01*
X341189D01*
X348689Y63750D01*
X365311D01*
X369000Y67439D01*
X383250Y53189D01*
Y47805D01*
X383237Y47771D01*
G03Y46229I2063J-771D01*
G01X383250Y46195D01*
Y38311D01*
X381689Y36750D01*
X379811D01*
X375811Y40750D01*
X370811D01*
X369250Y42311D01*
Y47311D01*
X368460Y48101D01*
X368446Y48129D01*
G03X367484Y49091I-1962J-1000D01*
G01X367456Y49105D01*
X366811Y49750D01*
X338189D01*
X333189Y44750D01*
X331189D01*
X330189Y43750D01*
X239189D01*
X238395Y42956D01*
G02X237714Y43201I-283J283D01*
G03X236211Y44567I-1503J-144D01*
G01X232591D01*
G03X231262Y42340I0J-1510D01*
G02X230910Y41750I-352J-190D01*
G01X228311D01*
X226311Y43750D01*
X68189D01*
X65689Y41250D01*
X60878D01*
Y53937D01*
G03X53937Y60878I-6941J0D01*
G01X3937D01*
G37*
G36*
G01X416390Y42126D02*
G03X409449Y49067I-6941J0D01*
G01X393701D01*
G03X386760Y42126I0J-6941D01*
G01Y20648D01*
X348673D01*
Y39961D01*
G03X335185I-6744J0D01*
G01Y20648D01*
X60878D01*
Y39750D01*
X66311D01*
X68811Y42250D01*
X75220D01*
G02X75469Y41537I0J-400D01*
G03X76410Y38847I942J-1180D01*
G01X80031D01*
G03X80973Y41537I0J1510D01*
G02X81222Y42250I249J313D01*
G01X90968D01*
G02X91217Y41537I0J-400D01*
G03X92158Y38847I942J-1180D01*
G01X95779D01*
G03X96721Y41537I0J1510D01*
G02X96970Y42250I249J313D01*
G01X106716D01*
G02X106965Y41537I0J-400D01*
G03X107907Y38847I942J-1180D01*
G01X111527D01*
G03X112469Y41537I0J1510D01*
G02X112718Y42250I249J313D01*
G01X122464D01*
G02X122713Y41537I0J-400D01*
G03X123655Y38847I942J-1180D01*
G01X127275D01*
G03X128217Y41537I0J1510D01*
G02X128466Y42250I249J313D01*
G01X138212D01*
G02X138461Y41537I0J-400D01*
G03X139403Y38847I942J-1180D01*
G01X143023D01*
G03X143965Y41537I0J1510D01*
G02X144214Y42250I249J313D01*
G01X153960D01*
G02X154209Y41537I0J-400D01*
G03X155150Y38847I942J-1180D01*
G01X158771D01*
G03X159713Y41537I0J1510D01*
G02X159962Y42250I249J313D01*
G01X169708D01*
G02X169957Y41537I0J-400D01*
G03X170898Y38847I942J-1180D01*
G01X174519D01*
G03X175461Y41537I0J1510D01*
G02X175710Y42250I249J313D01*
G01X185456D01*
G02X185705Y41537I0J-400D01*
G03X186646Y38847I942J-1180D01*
G01X190267D01*
G03X191209Y41537I0J1510D01*
G02X191458Y42250I249J313D01*
G01X193208D01*
G02X193467Y41545I0J-400D01*
G03X194444Y38885I978J-1150D01*
G01X198073D01*
G03X199051Y41545I0J1510D01*
G02X199310Y42250I259J305D01*
G01X225689D01*
X227689Y40250D01*
X237811D01*
X239811Y42250D01*
X240574D01*
G02X240823Y41537I0J-400D01*
G03X241765Y38847I942J-1180D01*
G01X245385D01*
G03X246327Y41537I0J1510D01*
G02X246576Y42250I249J313D01*
G01X263799D01*
G02X264080Y41565I0J-400D01*
G03X265140Y38980I1060J-1075D01*
G01X268910D01*
G03X269970Y41565I0J1510D01*
G02X270251Y42250I281J285D01*
G01X279647D01*
G02X279928Y41565I0J-400D01*
G03X280987Y38980I1060J-1075D01*
G01X284758D01*
G03X285818Y41565I0J1510D01*
G02X286099Y42250I281J285D01*
G01X295395D01*
G02X295676Y41565I0J-400D01*
G03X296735Y38980I1060J-1075D01*
G01X300506D01*
G03X301566Y41565I0J1510D01*
G02X301847Y42250I281J285D01*
G01X310967D01*
G02X311284Y41607I0J-400D01*
G03X312483Y39180I1200J-917D01*
G01X316254D01*
G03X317454Y41607I0J1510D01*
G02X317771Y42250I317J243D01*
G01X326595D01*
G02X326953Y41671I0J-400D01*
G03X328302Y39485I1350J-676D01*
G01X331931D01*
G03Y42505I0J1510D01*
G01X331549D01*
G02X331407Y42846I0J200D01*
G01X331811Y43250D01*
X333811D01*
X338811Y48250D01*
X366189D01*
X367750Y46689D01*
Y41689D01*
X370189Y39250D01*
X375189D01*
X379189Y35250D01*
X382311D01*
X384750Y37689D01*
Y53811D01*
X353250Y85311D01*
Y88811D01*
X351311Y90750D01*
X319689D01*
X318689Y89750D01*
X317311D01*
X313811Y93250D01*
X303689D01*
X299689Y89250D01*
X288811D01*
X285311Y92750D01*
X269689D01*
X266689Y89750D01*
X253311D01*
X249811Y93250D01*
X190557D01*
G03X187243I-1657J-1450D01*
G01X175811D01*
X173811Y95250D01*
X153311D01*
X136811Y111750D01*
X132311D01*
X124311Y119750D01*
X103189D01*
X100750Y117311D01*
Y105189D01*
X108750Y97189D01*
Y84811D01*
X106250Y82311D01*
Y72750D01*
X84811D01*
X63311Y94250D01*
X35189D01*
X32689Y91750D01*
X27811D01*
X25250Y94311D01*
Y128311D01*
X22311Y131250D01*
X3004D01*
Y286614D01*
G02X3937Y287547I933J0D01*
G01X193177D01*
G02X193514Y286932I0J-400D01*
G03X206880I6683J-4255D01*
G02X207217Y287547I337J215D01*
G01X291579D01*
G02X291917Y286933I0J-400D01*
G03X305327I6705J-4256D01*
G02X305665Y287547I338J214D01*
G01X822835D01*
G02X823768Y286614I0J-933D01*
G01Y3937D01*
G02X822835Y3004I-933J0D01*
G01X417323D01*
G02X416390Y3937I0J933D01*
G01Y42126D01*
G37*
G36*
G01X351750Y84689D02*
X367939Y68500D01*
X364689Y65250D01*
X349311D01*
X341811Y72750D01*
X332311D01*
X330311Y74750D01*
X317189D01*
X316189Y73750D01*
X285189D01*
X283189Y71750D01*
X243311D01*
X242311Y72750D01*
X238545D01*
G02X238238Y73407I0J400D01*
G03X233022I-2608J2183D01*
G02X232715Y72750I-307J-257D01*
G01X107750D01*
Y81689D01*
X110250Y84189D01*
Y97811D01*
X102250Y105811D01*
Y116689D01*
X103811Y118250D01*
X123689D01*
X131689Y110250D01*
X136189D01*
X152689Y93750D01*
X173189D01*
X175189Y91750D01*
X186691D01*
X186710Y91571D01*
G03X191090I2190J229D01*
G01X191109Y91750D01*
X249189D01*
X252689Y88250D01*
X267311D01*
X270311Y91250D01*
X284689D01*
X288189Y87750D01*
X300311D01*
X304311Y91750D01*
X313189D01*
X316689Y88250D01*
X319311D01*
X320311Y89250D01*
X350689D01*
X351750Y88189D01*
Y84689D01*
G37*
%LPD*%
G75*
G36*
G01X323999Y53390D02*
G02X324000Y56410I1J1510D01*
G01X327400D01*
G02Y53390I0J-1510D01*
G01X323999D01*
G37*
G36*
G01X315800Y55890D02*
G02Y58910I0J1510D01*
G01X319201D01*
G02X319200Y55890I-1J-1510D01*
G01X315800D01*
G37*
G36*
G01X304799D02*
G02X304800Y58910I1J1510D01*
G01X308200D01*
G02Y55890I0J-1510D01*
G01X304799D01*
G37*
G36*
G01X286799Y56390D02*
G02X286800Y59410I1J1510D01*
G01X290200D01*
G02Y56390I0J-1510D01*
G01X286799D01*
G37*
G36*
G01X267999Y55990D02*
G02X268000Y59010I1J1510D01*
G01X271000D01*
G02Y55990I0J-1510D01*
G01X267999D01*
G37*
G36*
G01X259073Y56300D02*
G02Y59300I-73J1500D01*
G01X261927D01*
G02Y56300I73J-1500D01*
G01X259073D01*
G37*
G36*
G01X250573Y56400D02*
G02Y59400I-73J1500D01*
G01X253427D01*
G02Y56400I73J-1500D01*
G01X250573D01*
G37*
G36*
G01X205300Y53390D02*
G02Y56410I0J1510D01*
G01X208701D01*
G02X208700Y53390I-1J-1510D01*
G01X205300D01*
G37*
G36*
G01X194773Y52900D02*
G02Y55900I-73J1500D01*
G01X197627D01*
G02Y52900I73J-1500D01*
G01X194773D01*
G37*
G36*
G01X186938Y52800D02*
G02Y55800I-73J1500D01*
G01X189627D01*
G02Y52800I73J-1500D01*
G01X186938D01*
G37*
G36*
G01X179073Y52900D02*
G02Y55900I-73J1500D01*
G01X181727D01*
G02Y52900I73J-1500D01*
G01X179073D01*
G37*
G36*
G01X170290Y48090D02*
G02Y51110I0J1510D01*
G01X174061D01*
G02X174060Y48090I-1J-1510D01*
G01X170290D01*
G37*
G36*
G01X163063Y52890D02*
G02Y55910I0J1510D01*
G01X166464D01*
G02X166463Y52890I-1J-1510D01*
G01X163063D01*
G37*
G36*
G01X155289Y47100D02*
G02X155290Y50120I1J1510D01*
G01X159060D01*
G02Y47100I0J-1510D01*
G01X155289D01*
G37*
G36*
G01X147315Y52890D02*
G02Y55910I0J1510D01*
G01X150716D01*
G02X150715Y52890I-1J-1510D01*
G01X147315D01*
G37*
G36*
G01X131600Y55890D02*
G02Y58910I0J1510D01*
G01X135001D01*
G02X135000Y55890I-1J-1510D01*
G01X131600D01*
G37*
G36*
G01X115800D02*
G02Y58910I0J1510D01*
G01X119201D01*
G02X119200Y55890I-1J-1510D01*
G01X115800D01*
G37*
G36*
G01X100050Y52890D02*
G02Y55910I0J1510D01*
G01X103451D01*
G02X103450Y52890I-1J-1510D01*
G01X100050D01*
G37*
G36*
G01X85299D02*
G02X85300Y55910I1J1510D01*
G01X88700D01*
G02Y52890I0J-1510D01*
G01X85299D01*
G37*
G36*
G01X79115Y59469D02*
G02Y62489I0J1510D01*
G01X82886D01*
G02X82885Y59469I-1J-1510D01*
G01X79115D01*
G37*
G36*
G01X9110Y260712D02*
G02X6090Y260713I-1510J1D01*
G01Y264483D01*
G02X9110I1510J0D01*
G01Y260712D01*
G37*
G36*
G01X15100Y254750D02*
G02X12080Y254751I-1510J1D01*
G01Y258521D01*
G02X15100I1510J0D01*
G01Y254750D01*
G37*
G36*
G01X39410Y253999D02*
G02X36390Y254000I-1510J1D01*
G01Y257500D01*
G02X39410I1510J0D01*
G01Y253999D01*
G37*
G36*
G01X9110Y248902D02*
G02X6090I-1510J0D01*
G01Y252673D01*
G02X9110Y252672I1510J-1D01*
G01Y248902D01*
G37*
G36*
G01X36397Y246861D02*
X36381Y247035D01*
X36481Y250542D01*
X36489Y250550D01*
X36495Y250624D01*
G02X39503Y250639I1505J-123D01*
G01X39519Y250465D01*
X39419Y246957D01*
X39394Y246785D01*
G02X36397Y246861I-1494J216D01*
G37*
G36*
G01X400528Y242794D02*
G02X398368Y244905I-1090J1045D01*
G01X400768Y247314D01*
G02X402908Y245182I1070J-1066D01*
G01X400529Y242795D01*
X400528Y242794D01*
G37*
G36*
G01X15100Y242939D02*
G02X12080Y242940I-1510J1D01*
G01Y246710D01*
G02X15100I1510J0D01*
G01Y242939D01*
G37*
G36*
G01X39410Y239999D02*
G02X36390Y240000I-1510J1D01*
G01Y243500D01*
G02X39410I1510J0D01*
G01Y239999D01*
G37*
G36*
G01X390616Y239712D02*
X390725Y239846D01*
X393170Y242218D01*
X393181D01*
X393237Y242267D01*
G02X395280Y240044I991J-1139D01*
G01X395137Y239905D01*
X395143Y239898D01*
X392844Y237667D01*
X392707Y237562D01*
G02X390616Y239712I-919J1198D01*
G37*
G36*
G01X9110Y237090D02*
G02X6090Y237091I-1510J1D01*
G01Y240861D01*
G02X9110I1510J0D01*
G01Y237090D01*
G37*
G36*
G01X36397Y232861D02*
X36381Y233035D01*
X36481Y236542D01*
X36489Y236550D01*
X36495Y236624D01*
G02X39503Y236639I1505J-123D01*
G01X39519Y236465D01*
X39419Y232957D01*
X39394Y232785D01*
G02X36397Y232861I-1494J216D01*
G37*
G36*
G01X14600Y231129D02*
G02X11580I-1510J0D01*
G01Y234900D01*
G02X14600Y234899I1510J-1D01*
G01Y231129D01*
G37*
G36*
G01X39410Y225999D02*
G02X36390Y226000I-1510J1D01*
G01Y229500D01*
G02X39410I1510J0D01*
G01Y225999D01*
G37*
G36*
G01Y218999D02*
G02X36390Y219000I-1510J1D01*
G01Y222500D01*
G02X39410I1510J0D01*
G01Y218999D01*
G37*
G36*
G01X53370Y187640D02*
G02X50350I-1510J0D01*
G01Y191411D01*
G02X53370Y191410I1510J-1D01*
G01Y187640D01*
G37*
G36*
G01X200951Y187570D02*
G02X197931Y187525I-1510J-23D01*
G01X197882Y190925D01*
G02X200902Y190969I1510J22D01*
G01X200951Y187570D01*
G37*
G36*
G01X59379Y185890D02*
G02Y182870I0J-1510D01*
G01X55719D01*
G02X55720Y185890I1J1510D01*
G01X59379D01*
G37*
G36*
G01X241407Y180504D02*
G02X238393Y180697I-1507J97D01*
G01X238612Y184090D01*
G02X241626Y183896I1507J-97D01*
G01X241407Y180504D01*
G37*
G36*
G01X195638Y148605D02*
G02X193608Y150841I-1015J1118D01*
G01X196115Y153119D01*
X196116Y153120D01*
G02X198155Y150892I1024J-1110D01*
G01X195638Y148605D01*
G37*
G36*
G01X236385Y139289D02*
G02X233365Y139290I-1510J1D01*
G01Y143060D01*
G02X236385I1510J0D01*
G01Y139289D01*
G37*
G36*
G01X210551Y140538D02*
G02X210542Y137518I-5J-1510D01*
G01X206785Y137530D01*
G02X206795Y140550I5J1510D01*
G01X210551Y140538D01*
G37*
G36*
G01X205380Y135710D02*
G02Y132690I0J-1510D01*
G01X201898D01*
G02X201899Y135710I1J1510D01*
G01X205380D01*
G37*
G36*
G01X152180Y115499D02*
G02X149160Y115500I-1510J1D01*
G01Y118900D01*
G02X152180I1510J0D01*
G01Y115499D01*
G37*
G36*
G01X210769Y113771D02*
G02X207749I-1510J0D01*
G01Y117431D01*
G02X210769Y117430I1510J-1D01*
G01Y113771D01*
G37*
G36*
G01X273710Y108360D02*
G02X270690Y108345I-1510J-7D01*
G01X270675Y111824D01*
G02X273695Y111838I1510J7D01*
G01X273710Y108360D01*
G37*
G36*
G01X36300Y212122D02*
Y208373D01*
G02X33300I-1500J-73D01*
G01Y212127D01*
G02X36300I1500J73D01*
G01Y212122D01*
G37*
G36*
G01X33500Y203122D02*
Y199373D01*
G02X30500I-1500J-73D01*
G01Y203127D01*
G02X33500I1500J73D01*
G01Y203122D01*
G37*
G36*
G01X33637Y194000D02*
Y183653D01*
X33780Y183610D01*
G02X34850Y180100I-630J-2110D01*
G03X34879Y179817I154J-127D01*
G02X33809Y175920I-1379J-1717D01*
G01X33637Y175895D01*
Y172000D01*
X20137D01*
Y194000D01*
X33637D01*
G37*
G36*
G01X405311Y161750D02*
X414811D01*
X419750Y156811D01*
Y150189D01*
X417311Y147750D01*
X405811D01*
X405250Y147189D01*
Y146189D01*
X403811Y144750D01*
X402311D01*
X398311Y140750D01*
X392811D01*
X390811Y138750D01*
X380811D01*
X379250Y137189D01*
Y135189D01*
X373311Y129250D01*
X363689D01*
X362189Y130750D01*
X351189D01*
X345189Y136750D01*
X343689D01*
X341689Y138750D01*
X322689D01*
X319750Y141689D01*
Y144689D01*
X315250Y149189D01*
Y156689D01*
X306689Y165250D01*
X298689D01*
X298629Y165311D01*
X289189Y174750D01*
X275689D01*
X267250Y183189D01*
Y192689D01*
X256189Y203750D01*
X252189D01*
X248689Y207250D01*
X244189D01*
X222250Y229189D01*
Y245311D01*
X225689Y248750D01*
X368811D01*
X373058Y244503D01*
X373134Y244498D01*
G02X375198Y242434I-134J-2198D01*
G01X375203Y242358D01*
X376250Y241311D01*
Y228689D01*
X369250Y221689D01*
Y211811D01*
X370311Y210750D01*
X373311D01*
X381250Y202811D01*
Y196189D01*
X378750Y193689D01*
Y177811D01*
X380311Y176250D01*
X383311D01*
X385311Y174250D01*
X386689D01*
X389189Y176750D01*
X395504D01*
G02X395642I69J-1350D01*
G01X403811D01*
X406250Y174311D01*
Y167689D01*
X404750Y166189D01*
Y162311D01*
X405311Y161750D01*
G37*
G36*
G01X307505Y124052D02*
X307509D01*
X309573Y124142D01*
X309578D01*
G02X309696Y121444I122J-1346D01*
G01X309691D01*
X307626Y121354D01*
X307621Y121353D01*
G02X307505Y124052I-121J1347D01*
G37*
G36*
G01X309107Y116351D02*
X307051Y116374D01*
X307046D01*
G02X307077Y119074I-52J1351D01*
G01X307081D01*
X309137Y119051D01*
X309142D01*
G02X309111Y116351I52J-1351D01*
G01X309107D01*
G37*
G36*
G01X146517Y149103D02*
G02X141483I-2517J-1978D01*
G03X141168Y149750I-315J247D01*
G01X121189D01*
X118689Y152250D01*
X104189D01*
X88189Y168250D01*
X81189D01*
X58250Y191189D01*
Y196311D01*
X60189Y198250D01*
X75811D01*
X83811Y190250D01*
X93811D01*
X112311Y171750D01*
X127311D01*
X134811Y164250D01*
X145689D01*
X149250Y167811D01*
Y176811D01*
X161189Y188750D01*
X188311D01*
X206311Y170750D01*
X212311D01*
X217750Y165311D01*
Y156189D01*
X215311Y153750D01*
X211689D01*
X207689Y157750D01*
X191189D01*
X183750Y165189D01*
Y172689D01*
X183124Y173315D01*
G03X182441Y173023I-283J-282D01*
G02X180965Y171475I-1510J-38D01*
G01X177194Y171390D01*
G02X177125Y174410I-35J1510D01*
G01X180897Y174495D01*
G02X180969I36J-1510D01*
G03X181261Y175178I10J400D01*
G01X179689Y176750D01*
X172811D01*
X171811Y175750D01*
X166311D01*
X165250Y174689D01*
Y173901D01*
X165621D01*
X165648Y174070D01*
G02X167140Y175350I1492J-230D01*
G01X170910D01*
G02Y172330I0J-1510D01*
G01X167139D01*
G02X165962Y172895I1J1510D01*
G03X165250Y172645I-312J-250D01*
G01Y158189D01*
X158311Y151250D01*
X153311D01*
X151811Y149750D01*
X146832D01*
G03X146517Y149103I0J-400D01*
G37*
G36*
G01X197845Y78850D02*
X194074D01*
G02X194075Y81870I1J1510D01*
G01X197845D01*
G02Y78850I0J-1510D01*
G37*
G54D39*
X37600Y198800D03*
Y203700D03*
X40400Y207800D03*
Y212700D03*
G54D36*
X42717Y270472D03*
X492520Y262598D03*
X761417Y22798D03*
G54D37*
X235630Y174016D03*
X498425Y22798D03*
X755512Y262598D03*
G54D35*
X42717Y191732D03*
G54D38*
X804032Y27032D03*
Y67032D03*
G54D34*
X11500Y68500D03*
X12000Y279000D03*
X816000Y280000D03*
G54D33*
X45669Y77185D03*
Y172460D03*
%LPC*%
G75*
G36*
G01X83106Y188833D02*
X83189Y188750D01*
X93189D01*
X111689Y170250D01*
X126689D01*
X134189Y162750D01*
X146311D01*
X150750Y167189D01*
Y176189D01*
X161811Y187250D01*
X187689D01*
X198937Y176002D01*
G03X199902Y175037I1963J998D01*
G01X205689Y169250D01*
X211689D01*
X216250Y164689D01*
Y156811D01*
X214689Y155250D01*
X212311D01*
X208311Y159250D01*
X191811D01*
X185250Y165811D01*
Y173311D01*
X180311Y178250D01*
X172189D01*
X171189Y177250D01*
X165689D01*
X163750Y175311D01*
Y158811D01*
X157689Y152750D01*
X152689D01*
X151189Y151250D01*
X121811D01*
X119311Y153750D01*
X104811D01*
X88811Y169750D01*
X81811D01*
X59750Y191811D01*
Y195689D01*
X60811Y196750D01*
X75189D01*
X81333Y190606D01*
X81345Y190548D01*
G03X83048Y188845I2155J452D01*
G01X83106Y188833D01*
G37*
G36*
G01X396926Y175250D02*
X403189D01*
X404750Y173689D01*
Y168311D01*
X403250Y166811D01*
Y161689D01*
X404689Y160250D01*
X414189D01*
X417129Y157311D01*
X418250Y156189D01*
Y150811D01*
X416689Y149250D01*
X405189D01*
X403750Y147811D01*
Y146811D01*
X403189Y146250D01*
X401689D01*
X397689Y142250D01*
X392189D01*
X390189Y140250D01*
X380189D01*
X377750Y137811D01*
Y135811D01*
X372689Y130750D01*
X364311D01*
X362811Y132250D01*
X351811D01*
X345811Y138250D01*
X344311D01*
X342311Y140250D01*
X323311D01*
X321250Y142311D01*
Y145311D01*
X316750Y149811D01*
Y157311D01*
X307311Y166750D01*
X299311D01*
X289811Y176250D01*
X276311D01*
X268750Y183811D01*
Y193311D01*
X256811Y205250D01*
X252811D01*
X249311Y208750D01*
X244811D01*
X223750Y229811D01*
Y244689D01*
X226311Y247250D01*
X264695D01*
X264729Y247237D01*
G03X266271I771J2063D01*
G01X266305Y247250D01*
X368189D01*
X374750Y240689D01*
Y229311D01*
X367750Y222311D01*
Y211189D01*
X369689Y209250D01*
X372689D01*
X379750Y202189D01*
Y196811D01*
X377250Y194311D01*
Y177189D01*
X379689Y174750D01*
X382689D01*
X384689Y172750D01*
X387311D01*
X389811Y175250D01*
X394220D01*
X394256Y175095D01*
G03X396890I1317J305D01*
G01X396926Y175250D01*
G37*
%LPD*%
G75*
G36*
G01X359109Y215175D02*
X357235Y216357D01*
Y216365D01*
X357154Y216425D01*
G02X358692Y218666I812J1091D01*
G01X358861Y218559D01*
X358866Y218567D01*
X360570Y217492D01*
X360694Y217389D01*
G02X359255Y215107I-867J-1048D01*
G01X359109Y215175D01*
G37*
G36*
G01X357131Y210131D02*
X357014Y212358D01*
X357026Y212523D01*
G02X359740Y212498I1356J-97D01*
G01X359750Y212299D01*
X359761D01*
X359866Y210293D01*
X359859Y210286D01*
X359858Y210204D01*
G02X357162Y209968I-1360J16D01*
G01X357131Y210131D01*
G37*
G36*
G01X346224Y210306D02*
X346295Y212525D01*
X346321Y212689D01*
G02X349017Y212612I1343J-213D01*
G01X349033Y212447D01*
X348962Y210234D01*
X348954Y210226D01*
X348947Y210154D01*
G02X346240Y210141I-1354J123D01*
G01X346224Y210306D01*
G37*
G36*
G01X352031Y212769D02*
G02X354739Y213027I1354J129D01*
G01X354948Y210837D01*
G02X352240Y210578I-1354J-129D01*
G01X352031Y212769D01*
G37*
G36*
G01X341838Y215882D02*
G02X344558Y215937I1360J27D01*
G01X344602Y213717D01*
G02X341882Y213663I-1360J-27D01*
G01X341838Y215882D01*
G37*
G36*
G01X329942Y236759D02*
X332041Y234668D01*
X332045Y234664D01*
G02X330148Y232742I-903J-1006D01*
G01X330145Y232745D01*
X328036Y234845D01*
X328033Y234848D01*
G02X329939Y236762I911J999D01*
G01X329942Y236759D01*
G37*
G36*
G01X335947Y217939D02*
G02X338667Y217982I1360J22D01*
G01X338701Y215752D01*
G02X335981Y215710I-1360J-21D01*
G01X335947Y217939D01*
G37*
G36*
G01X325999Y219130D02*
G02X328049Y220918I1025J894D01*
G01X329534Y219215D01*
G02X327485Y217426I-1025J-895D01*
G01X325999Y219130D01*
G37*
G36*
G01X337566Y211648D02*
G02X340286Y211699I1360J26D01*
G01X340327Y209480D01*
G02X337607Y209430I-1360J-25D01*
G01X337566Y211648D01*
G37*
G36*
G01X330256Y214834D02*
G02X332976Y214886I1360J26D01*
G01X333018Y212687D01*
G02X330298Y212634I-1360J-26D01*
G01X330256Y214834D01*
G37*
G36*
G01X316069Y236350D02*
G02Y239050I-69J1350D01*
G01X319031D01*
G02Y236350I69J-1350D01*
G01X316069D01*
G37*
G36*
G01X322950Y208769D02*
G02X320250I-1350J-69D01*
G01Y210931D01*
G02X322950I1350J69D01*
G01Y208769D01*
G37*
G36*
G01X318550Y213169D02*
G02X315850I-1350J-69D01*
G01Y215231D01*
G02X318550I1350J69D01*
G01Y213169D01*
G37*
G54D40*
X350197Y231103D03*
G54D15*
X17500Y190200D03*
X16844Y203100D03*
X13090Y231129D03*
Y234899D03*
X7600Y240861D03*
Y237091D03*
X13590Y242940D03*
Y254751D03*
X7600Y252672D03*
Y248902D03*
Y260713D03*
X13590Y258521D03*
Y246710D03*
X16900Y269000D03*
X7600Y264483D03*
X28400Y81400D03*
X30000Y136000D03*
X29700Y141200D03*
X26500Y181800D03*
X33500Y178100D03*
X33150Y181500D03*
X29400Y180000D03*
X23100Y181800D03*
X33500Y196100D03*
X32000Y203200D03*
Y199300D03*
X41200Y90300D03*
X42000Y96000D03*
X41500Y100800D03*
X40500Y124300D03*
X37600Y198800D03*
X37900Y195300D03*
X40400Y212700D03*
X34800Y208300D03*
X40400Y207800D03*
X34800Y212200D03*
X37600Y203700D03*
X44861Y227261D03*
X37900Y219000D03*
Y222500D03*
Y229500D03*
Y226000D03*
Y240000D03*
Y243500D03*
Y233000D03*
X38000Y236500D03*
X44400Y250400D03*
X37900Y257500D03*
Y254000D03*
Y247000D03*
X38000Y250500D03*
X46800Y274500D03*
X62900Y79900D03*
X60800Y87500D03*
X53500Y120400D03*
X57600Y136900D03*
X56100Y130700D03*
X52643Y130800D03*
X58000Y141750D03*
X58800Y177000D03*
X51860Y187640D03*
Y191410D03*
X59379Y184380D03*
X55720D03*
X57400Y210700D03*
X57009Y230009D03*
X57600Y226600D03*
X57500Y223200D03*
X57287Y219806D03*
X56724Y243300D03*
X56800Y249613D03*
X58102Y246471D03*
X57800Y253900D03*
X50000Y270000D03*
X57800Y264100D03*
X64700Y272500D03*
X57800Y267500D03*
X80031Y40357D03*
X76411D03*
X79700Y67500D03*
X79115Y60979D03*
X78300Y64300D03*
X69235Y99735D03*
X68200Y94900D03*
Y91500D03*
X66500Y128000D03*
X65500Y123800D03*
X74800Y191000D03*
X72600Y244800D03*
X75600Y246700D03*
X79000Y246900D03*
X69400Y246000D03*
X75300Y259900D03*
X78200Y275600D03*
X71800Y268800D03*
X66800Y275200D03*
X74000Y271400D03*
X92159Y40357D03*
X89400Y58200D03*
X83600Y57600D03*
X88700Y54400D03*
X85300D03*
X90600Y63200D03*
X94000Y63300D03*
X82885Y60979D03*
X90000Y91000D03*
X91500Y84000D03*
X94500Y76200D03*
X89800Y87300D03*
X86100Y97700D03*
X90500Y101000D03*
X86500Y113500D03*
X80500D03*
X85500Y135400D03*
X83500Y191000D03*
X86900D03*
X84700Y197100D03*
X92900Y204008D03*
X89500Y204000D03*
X85898Y200598D03*
X95200Y216200D03*
X90812Y215000D03*
X80563Y214700D03*
X88900Y246700D03*
X82400Y246600D03*
X82100Y259600D03*
X80500Y269500D03*
X83900D03*
X95779Y40357D03*
X107907D03*
X109700Y60000D03*
X104400Y57700D03*
X96800Y53300D03*
X103450Y54400D03*
X100050D03*
X109600Y63700D03*
X96200Y60700D03*
X97900Y76200D03*
X106100Y158700D03*
X97100Y189200D03*
X110000Y201900D03*
X107740Y204460D03*
X102000Y203200D03*
X100600Y221100D03*
X110166Y239500D03*
X109500Y258300D03*
X97600Y246500D03*
X104900Y248800D03*
X120000Y40700D03*
X123655Y40357D03*
X111527D03*
X121400Y60100D03*
X120200Y45610D03*
X119200Y57400D03*
X115800D03*
X111200Y67200D03*
X114800Y60700D03*
X121170Y80900D03*
X121295Y77502D03*
X126000Y86200D03*
X125787Y78813D03*
X120700Y135500D03*
X118500Y125500D03*
X112550Y142800D03*
X119600Y143300D03*
X111900Y209000D03*
X112800Y225400D03*
X112700Y221200D03*
Y231400D03*
X136600Y44800D03*
X139403Y40357D03*
X127275D03*
X138000Y49800D03*
X138574Y57924D03*
X131600Y57400D03*
X135000D03*
X136400Y60600D03*
X130400D03*
X136469Y89902D03*
X130315Y90533D03*
X134200Y86100D03*
X137138Y76512D03*
X129300Y84900D03*
X136600Y93300D03*
X133558Y91779D03*
X136500Y104923D03*
Y101523D03*
X130000Y121000D03*
X136540Y108620D03*
X133975Y129141D03*
X130563Y125200D03*
X127500Y129180D03*
X126950Y125200D03*
X133786Y134700D03*
X130300Y135000D03*
X135412Y141400D03*
X138600Y146300D03*
X131500Y149000D03*
X136156Y138025D03*
X131762Y141796D03*
X127200Y158700D03*
X137300Y158900D03*
X132700Y158600D03*
X140800Y158900D03*
X140000Y195500D03*
X137100Y188900D03*
X128000Y203300D03*
X143023Y40357D03*
X155151D03*
X144995Y57995D03*
X143700Y54503D03*
X154615Y54500D03*
X155290Y48610D03*
X143688Y48350D03*
X147315Y54400D03*
X150715D03*
X153000Y67800D03*
X152811Y84300D03*
X150894Y76497D03*
X154294Y76506D03*
X150670Y102720D03*
X154550Y106200D03*
X151080Y99344D03*
X154550Y102800D03*
X150670Y115500D03*
Y118900D03*
X157229Y119218D03*
X153693Y124807D03*
X147808Y145208D03*
X142900Y138595D03*
X146400D03*
X150804Y158896D03*
X144500Y158900D03*
X157000Y169194D03*
X146980Y200580D03*
X153000Y201900D03*
X153500Y210000D03*
X146396Y207675D03*
X142997Y207891D03*
X150000Y210100D03*
X146500Y236500D03*
X146000Y231000D03*
X155300Y254000D03*
X144200Y270700D03*
X158771Y40357D03*
X170899D03*
X169600Y53000D03*
X159957Y51932D03*
X159060Y48610D03*
X170290Y49600D03*
X166463Y54400D03*
X163063D03*
X167500Y68000D03*
X164000Y65000D03*
X172199Y91591D03*
X172300Y107189D03*
X158305Y112180D03*
X157500Y149025D03*
X161900Y161700D03*
X167581Y164084D03*
X170910Y173840D03*
X167140D03*
X165900Y181500D03*
X163700Y178900D03*
X169800Y181448D03*
X165700Y254000D03*
X174519Y40357D03*
X186647D03*
X185000Y51600D03*
X175758Y52879D03*
X174060Y49600D03*
X186865Y54300D03*
X181800Y54400D03*
X179000D03*
X179800Y65700D03*
X176900Y67500D03*
X180700Y78500D03*
X184300D03*
X183726Y106353D03*
X187500Y106500D03*
X173000Y97000D03*
X183344Y94056D03*
X179400Y94200D03*
X181732Y97500D03*
X178000Y97300D03*
X175787Y127000D03*
X176700Y144875D03*
X177200Y148700D03*
X181000Y167500D03*
X180931Y172985D03*
X177159Y172900D03*
X186300Y172400D03*
X174739Y207381D03*
X187000Y209500D03*
X198073Y40395D03*
X194445D03*
X190267Y40357D03*
X191700Y52100D03*
X201500Y54500D03*
X189700Y54300D03*
X197700Y54400D03*
X194700D03*
X190100Y68700D03*
X196900D03*
X193500D03*
X194075Y80360D03*
X197845D03*
X202200Y89500D03*
X198500Y83800D03*
X193485Y83724D03*
X191500Y94100D03*
X188900Y91800D03*
X193005Y97155D03*
X195989Y95300D03*
X189106Y97235D03*
X201650Y111200D03*
X201899Y134200D03*
X194900Y124200D03*
X197140Y152010D03*
X194623Y149723D03*
X191200Y181068D03*
X199441Y187547D03*
X199392Y190947D03*
X202761Y186811D03*
X195630Y192770D03*
X198198Y206374D03*
X194800Y206100D03*
X201596Y206504D03*
X195000Y234000D03*
X210900Y57600D03*
X205300Y54900D03*
X208700D03*
X214942Y67242D03*
X211600Y82100D03*
X212300Y85500D03*
X207200Y106000D03*
X209259Y113771D03*
Y117430D03*
X206605Y121741D03*
X209900Y120900D03*
X205380Y134200D03*
X210547Y139028D03*
X206790Y139040D03*
X215100Y194200D03*
X207861Y188540D03*
X215100Y199400D03*
X205000Y206500D03*
X215384Y202984D03*
X216000Y219500D03*
X208800D03*
X212500D03*
X206000Y234000D03*
X229300Y42950D03*
X232591Y43057D03*
X219900Y39100D03*
X223475Y53300D03*
X219899Y56800D03*
X233981Y59125D03*
X221400Y64500D03*
X230400Y63000D03*
X223800Y61700D03*
X230000Y66400D03*
X229036Y83000D03*
X226500Y94450D03*
X227850Y97575D03*
X230875Y106300D03*
X227894Y104600D03*
X232600Y95300D03*
X227800Y101200D03*
X233452Y108588D03*
X228000Y108304D03*
Y139700D03*
X232921Y167505D03*
X227870Y170252D03*
X224200Y180200D03*
X232560Y204250D03*
X227000Y275500D03*
X236211Y43057D03*
X245385Y40357D03*
X241765D03*
X244400Y50600D03*
X238800Y45300D03*
X240200Y59275D03*
X247500Y60000D03*
X235400Y63400D03*
X243200Y73700D03*
X240300Y67200D03*
X246600Y73700D03*
X244759Y85200D03*
X236700Y88500D03*
X241200Y94900D03*
X244800Y100700D03*
X235075Y105600D03*
X234875Y139290D03*
Y143060D03*
X244715Y159785D03*
X239900Y180600D03*
X247596Y174667D03*
X240119Y183993D03*
X240100Y191000D03*
X246689Y196687D03*
X254600Y41100D03*
X261900Y44900D03*
X265140Y40490D03*
X264700Y59400D03*
X256200Y59200D03*
X259000Y57800D03*
X250500Y57900D03*
X262000Y57800D03*
X253500Y57900D03*
X264500Y73100D03*
X253700Y75875D03*
X250300Y73800D03*
X264125Y79350D03*
X259820Y103454D03*
X262131Y100959D03*
X258634Y95850D03*
X263775Y140327D03*
X257977Y163423D03*
X264600Y173100D03*
X257687Y169870D03*
X253500Y174360D03*
X261300Y188300D03*
X253300Y189834D03*
X262700Y191500D03*
X261200Y209700D03*
X263600Y239850D03*
Y252700D03*
X257500Y266645D03*
X260500Y264630D03*
X269800Y44800D03*
X275300Y44900D03*
X278700Y44800D03*
X268910Y40490D03*
X278868Y56000D03*
X274000Y55800D03*
X271000Y57500D03*
X268000D03*
X275200Y78700D03*
X275900Y88200D03*
X280100Y89100D03*
X272200Y108352D03*
X272185Y111831D03*
X278075Y116475D03*
X272300Y129442D03*
X268900Y129386D03*
X280400Y129225D03*
X272300Y149900D03*
X267187Y149800D03*
X278000Y141900D03*
X273900Y156198D03*
X270500Y163200D03*
X274100Y163300D03*
X267456Y160156D03*
X267100Y156200D03*
X272380Y159240D03*
X270500Y156250D03*
X268283Y173035D03*
X278300Y173300D03*
X269772Y188274D03*
X276910Y189400D03*
X273060Y189374D03*
X266140Y191850D03*
X270341Y211835D03*
X278450Y216800D03*
X265259Y216659D03*
X270774Y222226D03*
X274700Y222100D03*
X275400Y237900D03*
X267275Y253400D03*
X265500Y249300D03*
X269800Y250700D03*
X278700Y254240D03*
X275300Y254100D03*
X267000Y271300D03*
X284758Y40490D03*
X280988D03*
X292500Y60500D03*
X284000Y55800D03*
X286800Y57900D03*
X290200D03*
X288700Y71100D03*
X292100D03*
X295300Y66200D03*
X288400Y94200D03*
X288100Y99500D03*
X281005Y99105D03*
X281475Y116475D03*
X286500Y119900D03*
X286600Y136000D03*
X287071Y173154D03*
X282950Y181350D03*
X282460Y189400D03*
X286300Y191885D03*
X287700Y211900D03*
X293300Y212400D03*
X291201Y225025D03*
X287802Y225200D03*
X295300Y238100D03*
X287600D03*
X287400Y254100D03*
X295500Y253500D03*
X281599Y261799D03*
X287250Y269250D03*
X296736Y40490D03*
X300506D03*
X302400Y59500D03*
X300900Y46900D03*
X308200Y57400D03*
X304800D03*
X297150Y91100D03*
X309400Y82100D03*
X299800Y85950D03*
Y82300D03*
X304400Y88400D03*
X306100Y90600D03*
X301300Y97000D03*
X301600Y93300D03*
X303400Y98500D03*
X303376Y95200D03*
X299300Y98500D03*
X296564Y136311D03*
Y127500D03*
X296531Y133061D03*
X301109Y146156D03*
X300700Y142850D03*
X297000Y160200D03*
X307231Y164059D03*
X310579Y182800D03*
X306612Y171882D03*
X304400Y182000D03*
X302591Y173906D03*
X309112Y171960D03*
X309200Y180500D03*
X305091Y173888D03*
X301745Y181788D03*
X307200Y182000D03*
X296600Y189100D03*
X305300Y203125D03*
X307300Y224900D03*
X304400D03*
X309900D03*
X298900Y253300D03*
X309400Y253600D03*
X306000D03*
X302600D03*
X304300Y262900D03*
X309000Y266700D03*
X311300Y277800D03*
X321900Y44000D03*
X312484Y40690D03*
X316254D03*
X314800Y48625D03*
X311950Y50800D03*
X320400Y48600D03*
X311598Y57522D03*
X322548Y58300D03*
X324000Y54900D03*
X324176Y48600D03*
X315800Y57400D03*
X319200D03*
X323882Y71643D03*
X318882D03*
X312400Y79700D03*
X312150Y100682D03*
X326000Y254100D03*
X315500D03*
X322500Y254200D03*
X319000D03*
X311400Y269200D03*
X326100Y267000D03*
X318600Y264300D03*
X313824Y280255D03*
X316945Y281606D03*
X316400Y276800D03*
X319400Y278800D03*
X322700Y277700D03*
X321600Y282500D03*
X325100Y281500D03*
X331931Y40995D03*
X328303D03*
X331300Y48475D03*
X327577D03*
X328300Y58200D03*
X327400Y54900D03*
X333600Y63800D03*
X337000Y74202D03*
X328882Y71643D03*
X356432Y43657D03*
X356971Y37700D03*
X349900Y263800D03*
X342600Y277900D03*
X364600Y44298D03*
X367497Y41042D03*
X363604D03*
X371457Y37642D03*
X367520D03*
X366484Y47129D03*
X362626Y47068D03*
X366700Y68700D03*
X373000Y242300D03*
Y236000D03*
Y238900D03*
X385300Y47000D03*
X388000Y72963D03*
X382700Y275300D03*
X386100D03*
X379300D03*
X394229Y241128D03*
X391788Y238760D03*
X399438Y243839D03*
X401838Y246248D03*
X390500Y268800D03*
X393000Y275000D03*
X400900Y273000D03*
X391000Y265000D03*
X417000Y258000D03*
X416128Y272896D03*
X425400Y9103D03*
X422000D03*
X428800D03*
X432200D03*
X430000Y21500D03*
Y27358D03*
X424543Y22208D03*
Y27900D03*
X426405Y25054D03*
X427000Y17000D03*
X423500Y16885D03*
X423000Y43900D03*
X430000Y30758D03*
X424536Y34800D03*
X430000Y34158D03*
X424599Y31300D03*
X422986Y40350D03*
X430000Y244450D03*
X426600D03*
X420000Y244000D03*
X420500Y257800D03*
X433129Y245783D03*
X423600Y246700D03*
X423000Y274000D03*
X433300Y274100D03*
X426600D03*
X429900Y274940D03*
X442100Y7006D03*
X437061Y10393D03*
X434900Y6925D03*
X446800Y9900D03*
X438300Y6925D03*
X449600Y5900D03*
X446200D03*
X446100Y18700D03*
X441390Y28680D03*
X436240Y26300D03*
X449734Y18681D03*
X441281Y17025D03*
X436100Y30900D03*
X436106Y34506D03*
X435700Y243250D03*
X440600Y274300D03*
X449400Y273700D03*
X436600Y275000D03*
X450200Y9800D03*
X451300Y21700D03*
X464000Y275200D03*
X460400D03*
X452500D03*
X469000D03*
X472400Y275100D03*
X466500Y272800D03*
X472101Y266090D03*
X475500Y265900D03*
X479000D03*
X493000Y119299D03*
X495400Y183500D03*
X482400Y266200D03*
X498500Y88995D03*
X508000Y119500D03*
X511500D03*
X504400Y183400D03*
X510675Y209700D03*
X505315Y268500D03*
X497002Y275400D03*
X522280Y89810D03*
X515502Y88998D03*
X518902Y88987D03*
X518200Y183400D03*
X514800D03*
X528985Y89975D03*
X533267Y89634D03*
X539574Y88990D03*
X533000Y119500D03*
X536400D03*
X528100D03*
X528400Y145041D03*
X541550Y183550D03*
X534750Y183600D03*
X538150D03*
X530214Y183481D03*
X531000Y228350D03*
X552900Y89100D03*
X542950Y89400D03*
X555500Y183500D03*
X548354Y183600D03*
X551754D03*
X548300Y209700D03*
X566000Y89100D03*
X572845Y183300D03*
X566897Y183405D03*
X561900Y183600D03*
X564398Y183481D03*
X569395Y183300D03*
X558300Y210000D03*
X561000Y222700D03*
X561196Y227366D03*
X564200Y224000D03*
X575000Y89100D03*
X587500Y88913D03*
X578400Y89100D03*
X588600Y124700D03*
X584800Y183300D03*
X576295Y183400D03*
X588475Y183300D03*
X578795D03*
X573600Y190100D03*
X586800Y213200D03*
X583800Y207200D03*
X580350Y207250D03*
X599500Y87500D03*
X590898Y89045D03*
X593400Y126000D03*
X592200Y145000D03*
X595744Y145041D03*
X599150Y180300D03*
X593475Y183275D03*
X601750Y182500D03*
X594350Y187725D03*
X591850D03*
X591363Y208387D03*
X602800Y203225D03*
X601200Y207700D03*
X612120Y121750D03*
X608360Y121800D03*
X608300Y144890D03*
X618500Y159000D03*
X605600Y186650D03*
X609345Y190100D03*
X607500Y188300D03*
X616100Y197400D03*
X634000Y97500D03*
X630700Y100500D03*
X624726Y107395D03*
X621100Y124900D03*
X625500Y159000D03*
X629000D03*
X622000D03*
X633319Y155008D03*
X631900Y175850D03*
X634748Y177708D03*
X633100Y198300D03*
X626300Y198250D03*
X629700Y198300D03*
X622873Y204200D03*
X642823Y88477D03*
X640677Y91115D03*
X638500Y94000D03*
X635000Y110500D03*
X638000Y107400D03*
X648500Y144000D03*
X636719Y154972D03*
X643500Y155000D03*
X640110Y155272D03*
X640461Y181410D03*
X642600Y186400D03*
X646000D03*
X636500Y198300D03*
X653600Y122400D03*
X656477Y148033D03*
X656642Y151430D03*
X656200Y144000D03*
X650500Y155000D03*
X661000Y173800D03*
X657722Y193800D03*
X661600Y197300D03*
X654851Y191978D03*
X663800Y199900D03*
X673100Y179455D03*
X673044Y190456D03*
X668732Y204555D03*
X666446Y202037D03*
X682600Y114300D03*
X689400Y178900D03*
X689547Y175500D03*
X686700Y187400D03*
X687456Y183944D03*
X705145Y93500D03*
X707209Y97500D03*
X698970Y118149D03*
X699241Y114759D03*
X709500Y143500D03*
X709900Y139900D03*
X701245Y183800D03*
X718900Y94000D03*
X726800Y95500D03*
X724200Y108400D03*
X714000Y118500D03*
X727448Y128893D03*
X714900Y131900D03*
X718200Y147000D03*
Y150400D03*
X718825Y155453D03*
X712700Y155978D03*
X724400Y176025D03*
X725500Y195500D03*
X727400Y227400D03*
X736900Y98500D03*
X730200Y94900D03*
X742100Y118200D03*
X736300Y118000D03*
X729400Y120200D03*
X732000Y122700D03*
X728900Y132976D03*
X727800Y136600D03*
X740300Y164700D03*
X727800Y176600D03*
X733000Y176200D03*
X739900Y212800D03*
X731000Y210200D03*
X739800Y216300D03*
X750100Y16100D03*
X749500Y101500D03*
X751300Y118200D03*
X754000Y115100D03*
X748800Y115800D03*
X757900Y124700D03*
X743100Y195500D03*
X743000Y211000D03*
X744100Y221900D03*
X743800Y215900D03*
X758916Y104250D03*
X762304Y103957D03*
X765500Y112000D03*
X769800Y133000D03*
X759400Y131000D03*
X771300Y140200D03*
X766600Y139800D03*
X762000Y281000D03*
X765400D03*
X774500Y31307D03*
X778000D03*
X787600Y183300D03*
X787800Y179900D03*
X793000Y174500D03*
X805500Y128000D03*
G54D20*
X196800Y62600D03*
X502500Y6200D03*
X538300Y15200D03*
X699000Y162255D03*
X756400Y110500D03*
X786500Y13500D03*
X782000Y137000D03*
X790500Y11000D03*
X799000Y121500D03*
Y125500D03*
X800400Y158500D03*
X799900Y168800D03*
X811000Y130000D03*
Y134000D03*
X809000Y149200D03*
X811000Y138000D03*
X811200Y141600D03*
X809500Y156900D03*
X809600Y160500D03*
X809700Y164300D03*
G54D12*
X14000Y104500D03*
X14400Y98000D03*
X14000Y109500D03*
X11500Y163700D03*
Y159000D03*
X7000Y163700D03*
Y159000D03*
X23400Y81550D03*
X25000Y77300D03*
X33000Y105000D03*
X30200Y145000D03*
Y149200D03*
X34000Y161500D03*
X30300Y157600D03*
X30200Y153400D03*
X37500Y105000D03*
X42000D03*
X37500Y264000D03*
X76200Y187200D03*
X82000Y177500D03*
X86500D03*
X90700Y177050D03*
X92800Y285600D03*
X100000Y267400D03*
X100700Y262900D03*
X97500Y285450D03*
X102000D03*
X106500Y285550D03*
X110700D03*
X113200Y146700D03*
X113100Y151000D03*
X117500Y146950D03*
X119000Y159100D03*
X114700Y158800D03*
X116500Y211200D03*
X134100Y96600D03*
X128500Y165000D03*
X129500Y252500D03*
X129000Y268000D03*
X166500Y241000D03*
X189000Y87700D03*
X192500Y161900D03*
X192600Y166700D03*
X216261Y74846D03*
X217000Y252900D03*
X217200Y258000D03*
X226900Y133300D03*
X221300Y255400D03*
X240130Y77300D03*
X236400Y95100D03*
X240565Y113365D03*
X249350Y199400D03*
X248300Y213500D03*
X258400Y65600D03*
X257000Y213500D03*
X252350Y202350D03*
X252700Y213500D03*
X253000Y267000D03*
X278200Y281350D03*
X294800Y94100D03*
X282686Y281336D03*
X321300Y88200D03*
X339638Y67138D03*
X334500Y266300D03*
X334300Y270500D03*
X335700Y278751D03*
X331500D03*
X353100Y56151D03*
X345089Y73089D03*
X343600Y270500D03*
X496711Y248999D03*
X527000Y225500D03*
X598814Y240095D03*
X615100Y238900D03*
X623900Y239600D03*
X646000Y46007D03*
X640000D03*
X654500Y46107D03*
X659811Y260757D03*
X657500Y258400D03*
X661308Y263698D03*
X655500Y270500D03*
X657787Y264179D03*
X656000Y261400D03*
X655523Y266616D03*
X658667Y267622D03*
X721200Y65100D03*
X732000Y63500D03*
X753500Y24007D03*
Y20007D03*
Y28507D03*
X755500Y16000D03*
X770500Y13007D03*
X767500Y24007D03*
X760500Y29000D03*
X761000Y16007D03*
X767500Y28507D03*
Y19507D03*
X764200Y44200D03*
X767500Y33207D03*
X759000Y37507D03*
X764500Y54000D03*
X764300Y49200D03*
X769500Y50000D03*
X761000Y58500D03*
X787500Y93000D03*
X783000D03*
X785830Y188700D03*
X785400Y202800D03*
X789000Y204979D03*
X789200Y214200D03*
Y209800D03*
X784500Y222500D03*
X789000Y223500D03*
X789200Y218700D03*
X786000Y228000D03*
Y232400D03*
X786200Y236900D03*
X786300Y241500D03*
X785000Y245800D03*
Y250200D03*
Y254900D03*
X792000Y83000D03*
X796500D03*
X792000Y87700D03*
X796500D03*
X799200Y98600D03*
X803100Y106000D03*
X799200Y102800D03*
X799000Y107100D03*
X803500Y116700D03*
Y112500D03*
X799000Y116100D03*
Y111900D03*
X789910Y187679D03*
X794110D03*
X798310Y187779D03*
X793500Y204979D03*
Y223500D03*
X793200Y228400D03*
Y232600D03*
Y237200D03*
Y242400D03*
X793300Y247200D03*
X795300Y260800D03*
X795400Y251700D03*
X795300Y256500D03*
Y265000D03*
X810100Y275000D03*
X812035Y271067D03*
X810100Y267339D03*
X812000Y263500D03*
G54D18*
X42717Y270472D03*
X235630Y75590D03*
X492520Y262598D03*
D03*
X761417Y22798D03*
D03*
X804032Y27032D03*
X794032D03*
X804032Y37032D03*
Y47032D03*
X794032Y37032D03*
Y47032D03*
X804032Y57032D03*
X794032D03*
X804032Y67032D03*
X794032D03*
G54D22*
X235630Y174016D03*
X498425Y22798D03*
D03*
X755512Y262598D03*
D03*
G54D24*
X303610Y110800D03*
X309000Y114700D03*
X306700D03*
X309194Y117700D03*
X306994Y117725D03*
X304149Y128349D03*
X307854Y130539D03*
X309700Y122796D03*
X309500Y132925D03*
X307298Y132697D03*
X307500Y122700D03*
X305050Y151150D03*
X309000Y137600D03*
X306961Y153717D03*
X306696Y158610D03*
X309000Y158806D03*
X309220Y153698D03*
X305800Y195400D03*
X305290Y187836D03*
X301320Y191060D03*
X303500Y195400D03*
X310500Y195600D03*
X308200D03*
X303480Y189100D03*
X301300Y188700D03*
X309700Y187997D03*
X307500Y188000D03*
X309100Y206800D03*
X317641Y90956D03*
X325081Y100631D03*
X322075Y100650D03*
X323120Y92400D03*
X319520Y92419D03*
X318900Y98000D03*
X317600Y93625D03*
X326162Y91438D03*
X315950Y98650D03*
X320992Y112180D03*
X319096Y113300D03*
X319418Y123225D03*
X315451Y123219D03*
X323900Y129900D03*
X325418Y127349D03*
X325746Y133702D03*
X323300Y147046D03*
X323550Y142104D03*
X326322Y138434D03*
X325763Y141958D03*
X319401Y149354D03*
X317698Y152311D03*
X325200Y149319D03*
X319704Y162804D03*
X323000Y153900D03*
X315384Y166733D03*
X324953Y161722D03*
X324200Y157800D03*
X324029Y166384D03*
X326234Y153969D03*
X323165Y171937D03*
X324436Y175705D03*
X326399Y169401D03*
X323500Y180063D03*
X311460Y172078D03*
X319942Y180524D03*
X323121Y182913D03*
X326408Y182292D03*
X312829Y181940D03*
X316844Y196010D03*
X319801Y194890D03*
X326550Y191600D03*
X323800Y192150D03*
X323789Y188117D03*
X320029Y184300D03*
X326500Y187900D03*
X311900Y188070D03*
X322256Y198618D03*
X323331Y196696D03*
X319500Y212100D03*
X325642Y202325D03*
X321600Y208700D03*
Y211000D03*
X317200Y213100D03*
X315585Y207787D03*
X324100Y208000D03*
X318700Y207800D03*
X311600Y207600D03*
X325200Y221700D03*
X319400Y216200D03*
X317200Y215300D03*
X313600Y237700D03*
X321400D03*
X316000D03*
X319100D03*
X329300Y87300D03*
X331200Y88600D03*
X330100Y100200D03*
Y98000D03*
X336750Y93500D03*
Y95704D03*
X328000Y92700D03*
X330900Y93400D03*
X333313Y103693D03*
X329415Y119923D03*
X333601Y120500D03*
X333534Y118040D03*
X333434Y106668D03*
X341200Y112569D03*
X338768Y116755D03*
Y119755D03*
X329308Y122386D03*
X338329Y135665D03*
X329031Y125428D03*
X335303Y135178D03*
X336900Y127600D03*
X333977Y127678D03*
X327854Y130434D03*
X338470Y138177D03*
X335450Y150900D03*
X327963Y142008D03*
X335514Y138220D03*
X338320Y141300D03*
X327390Y149106D03*
X336920Y146130D03*
X329421Y138228D03*
X327696Y146108D03*
X336190Y141970D03*
X330796Y146221D03*
X330163Y142008D03*
X332478Y138255D03*
X341342Y138224D03*
X333750Y145950D03*
X339491Y143163D03*
X329800Y150800D03*
X332000D03*
X330300Y158546D03*
X339784Y161847D03*
X335499Y153846D03*
X327800Y161500D03*
X336900Y161600D03*
X336800Y164434D03*
X341390Y153991D03*
X329161Y153830D03*
X335964Y158512D03*
X333742Y161624D03*
X332185Y153806D03*
X338421Y153802D03*
X334470Y164760D03*
X341400Y156700D03*
X331000Y164500D03*
X330900Y161700D03*
X333000Y158300D03*
X339747Y164478D03*
X341300Y169600D03*
X335400D03*
X339300Y174100D03*
X330821Y177402D03*
X333842Y177224D03*
X332300Y173900D03*
X339875Y177303D03*
X329442Y169463D03*
X327708Y177241D03*
X332353Y169522D03*
X337000Y174102D03*
X327600Y174174D03*
X330027Y174119D03*
X334700Y174100D03*
X336915Y177423D03*
X337863Y180545D03*
X334715Y180900D03*
X330280D03*
X332500D03*
X332100Y185600D03*
X338000Y185700D03*
X335000Y185500D03*
X335400Y196300D03*
X337800Y189200D03*
X326850Y193900D03*
X329972Y196400D03*
Y193559D03*
X333996Y192063D03*
X334707Y189383D03*
X337800Y192200D03*
X338048Y196250D03*
X342029Y196427D03*
X332800Y187700D03*
X326831Y196119D03*
X329313Y188000D03*
X337670Y213520D03*
X335739Y199317D03*
X336500Y204600D03*
X332974Y210874D03*
X338926Y211674D03*
X338967Y209455D03*
X331658Y212660D03*
X329028Y199931D03*
X339800Y207400D03*
X327216Y203902D03*
X330200Y216800D03*
X336000Y219750D03*
X328510Y218320D03*
X327024Y220024D03*
X337307Y217961D03*
X331616Y214860D03*
X337341Y215731D03*
X333036Y231910D03*
X327100Y237100D03*
X328945Y235846D03*
X331142Y233658D03*
X346596Y118163D03*
Y115163D03*
X343570Y112561D03*
X346495Y130000D03*
X349149Y124141D03*
X351500Y136000D03*
X343000Y126200D03*
X343146Y128473D03*
X347641Y133479D03*
X342533Y133822D03*
X357300Y128600D03*
X355400Y137100D03*
X354300Y128600D03*
X346300Y143000D03*
X342880Y146180D03*
X355447Y146528D03*
X344500Y141700D03*
X348675Y143326D03*
X350800Y138300D03*
X355342Y143424D03*
X348743Y146072D03*
X346000Y146043D03*
X346450Y149120D03*
X348743Y149100D03*
X355460Y149510D03*
X348432Y164844D03*
X346944Y156775D03*
X350550Y153280D03*
X342716Y161593D03*
X344300Y153800D03*
X344090Y156690D03*
X352000Y162000D03*
X348700Y161700D03*
X351600Y164300D03*
X355400Y152900D03*
X355413Y156050D03*
X351700Y167300D03*
X350700Y155600D03*
X345900Y161700D03*
X342188Y183361D03*
X355300Y174600D03*
X347200Y174300D03*
X344165Y169466D03*
X352200Y171800D03*
X350000Y177700D03*
X345562Y178700D03*
X347500Y169500D03*
X351600Y169600D03*
X353302Y182993D03*
X353321Y180128D03*
X342233Y185639D03*
X356900Y186100D03*
X349600Y194800D03*
X342760Y187810D03*
X342339Y192225D03*
X342342Y190024D03*
X349100Y191900D03*
X353625Y195045D03*
Y192045D03*
X356600Y195700D03*
X356700Y193300D03*
X345503Y193474D03*
X345500Y190500D03*
X349100Y189700D03*
X353342Y186124D03*
X349751Y187241D03*
X356800Y191000D03*
X345500Y184500D03*
X345631Y187420D03*
X351950Y214800D03*
X346500Y208350D03*
X345500Y213000D03*
X353594Y210707D03*
X347593Y210277D03*
X353385Y212898D03*
X345837Y199887D03*
X350409Y199755D03*
X353792Y208466D03*
X354700Y199900D03*
X343242Y213690D03*
X347664Y212476D03*
X355860Y216690D03*
X345300Y216700D03*
X343198Y215910D03*
X371900Y85400D03*
X364800Y91200D03*
X368600Y90700D03*
X361200Y90200D03*
X371950Y92500D03*
X364874Y98250D03*
X362803Y106035D03*
X357900Y99200D03*
X368600Y97500D03*
X357721Y91779D03*
X361200Y97500D03*
X365316Y108130D03*
X372700Y119663D03*
X370100Y119563D03*
X370000Y116563D03*
X364600Y137063D03*
X362111Y127142D03*
X362120Y124153D03*
X359421Y127128D03*
Y124008D03*
X372821Y125628D03*
X370121Y125528D03*
X367321Y122528D03*
X368026Y137118D03*
X364700Y134000D03*
X367992Y133982D03*
X358500Y137000D03*
X371176Y136890D03*
X359300Y130000D03*
X367900Y152550D03*
X368000Y146500D03*
X361700Y143300D03*
X364886Y140268D03*
X368026D03*
Y143418D03*
X364621Y143328D03*
X361726Y140268D03*
X361700Y146549D03*
X361500Y149500D03*
X364700Y152713D03*
X368026Y149718D03*
X368100Y165300D03*
X364600D03*
X367950Y159200D03*
X371157Y162320D03*
X371176Y158940D03*
X358477Y159300D03*
X361600Y159250D03*
X368100Y162200D03*
X358342Y165324D03*
X358576Y162090D03*
X358500Y155700D03*
X371100Y168700D03*
X364600Y174800D03*
X361500Y175000D03*
Y168500D03*
X368000D03*
X367906Y171458D03*
X364600Y171600D03*
X364607Y177103D03*
X370900Y171700D03*
X361200Y178500D03*
X361292Y181409D03*
X372400Y179100D03*
X369021Y180128D03*
X372600Y181400D03*
X361400Y187600D03*
X368455Y196455D03*
X371299Y196008D03*
X364792Y188743D03*
X364600Y186138D03*
X364895Y190941D03*
X369106Y191903D03*
X369200Y189100D03*
X361257Y193524D03*
Y190700D03*
X364947Y193141D03*
X361300Y184500D03*
X359222Y197700D03*
X369009Y186191D03*
X372700Y213700D03*
X369450Y212040D03*
X359750Y208390D03*
X359910Y214100D03*
X358498Y210220D03*
X358382Y212427D03*
X371100Y199500D03*
X365250Y208600D03*
X372800Y221600D03*
X369580Y218800D03*
X357966Y217516D03*
X359827Y216341D03*
X383350Y83350D03*
X383450Y90500D03*
X387200D03*
X387100Y83500D03*
X375800D03*
Y90500D03*
X379500Y83302D03*
Y90600D03*
X381600Y119900D03*
X381900Y113000D03*
X382596Y108600D03*
X385600Y116500D03*
X385200Y113137D03*
X385721Y119528D03*
X385479Y125569D03*
X381500Y123200D03*
X381600Y126427D03*
X385523Y122532D03*
X386708Y137118D03*
X383567Y137096D03*
X380475Y137016D03*
X380443Y130102D03*
X374200Y136994D03*
X387000Y143280D03*
X380398Y146568D03*
X383548D03*
X380398Y143418D03*
X383395Y143306D03*
X374200Y140144D03*
Y143294D03*
X380400Y152700D03*
X383575Y149603D03*
X380522Y149564D03*
X386853Y149640D03*
X377476Y149688D03*
X374200Y149494D03*
X374100Y159150D03*
X386800Y165300D03*
X380398Y165240D03*
X383781Y165235D03*
X386777Y162155D03*
X387000Y155850D03*
X386777Y159005D03*
X380500Y162025D03*
X383700Y162199D03*
X383500Y159000D03*
X374300Y155800D03*
X377500Y165240D03*
Y156000D03*
X384740Y180080D03*
X381720Y180220D03*
X381800Y183300D03*
X380540Y177370D03*
X380500Y168500D03*
X383693Y171424D03*
X383548Y168390D03*
X386600Y174900D03*
X380477Y171605D03*
X376830Y175640D03*
X376800Y178600D03*
X376742Y181524D03*
X381460Y195610D03*
X384390Y196470D03*
X381140Y187960D03*
X381280Y191550D03*
X384708Y188910D03*
X384600Y186100D03*
X376800Y193500D03*
X376900Y196600D03*
X373922Y193103D03*
X374000Y190350D03*
X379750Y213500D03*
X376300Y211000D03*
X382600Y222600D03*
X382750Y229000D03*
X379700Y219200D03*
X385947Y226500D03*
X385900Y218400D03*
X376300Y216200D03*
X390700Y89300D03*
X403726Y83826D03*
X403700Y90200D03*
X397300Y89168D03*
X400400Y92200D03*
Y98500D03*
X390750Y96500D03*
X394100Y91400D03*
Y99000D03*
X397100Y96600D03*
X393331Y118043D03*
X393351Y115107D03*
X397650Y115500D03*
X401749Y112418D03*
X401159Y119636D03*
X401353Y116562D03*
X396276Y120948D03*
X396251Y117999D03*
X393653Y121122D03*
X389700Y112363D03*
X398500Y125604D03*
X398512Y122815D03*
X401500Y125600D03*
X393482Y123982D03*
X396700Y128000D03*
X389914Y124536D03*
X393561Y127130D03*
X401500Y122600D03*
X401256Y128755D03*
X397800Y130000D03*
X390100Y127600D03*
X390205Y133858D03*
X392998Y133968D03*
X396148D03*
X396321Y136987D03*
X402561Y137000D03*
X399298Y137118D03*
X392998D03*
X389848D03*
X402400Y140163D03*
X389721Y143320D03*
X396148Y140268D03*
X399298D03*
X389848Y146568D03*
X393204Y146436D03*
X392998Y165240D03*
X396148Y155790D03*
X393208D03*
X399298Y165240D03*
X392599Y181686D03*
X400252Y182966D03*
X403600Y182400D03*
Y180200D03*
X402540Y171760D03*
X399300Y168400D03*
X402600Y174611D03*
X395573Y175400D03*
X393077Y168455D03*
X399385Y171686D03*
X396225D03*
X390025Y174672D03*
X393085Y171686D03*
Y174836D03*
X400352Y180171D03*
X397100Y181000D03*
X400301Y186099D03*
X397805Y192061D03*
X392600Y190600D03*
X396200Y194700D03*
X392624Y184537D03*
X389500Y193600D03*
X397307Y186607D03*
X395600Y184100D03*
Y190300D03*
X392700Y193563D03*
X403022Y192094D03*
X402967Y195005D03*
X389484Y190442D03*
X389300Y187700D03*
X402962Y189014D03*
X392596Y187541D03*
X397728Y189053D03*
X395641Y188045D03*
X392100Y213700D03*
X395700Y213600D03*
X389100Y224000D03*
X399700Y225000D03*
Y216400D03*
X395600Y224400D03*
X395700Y217000D03*
X391950Y220800D03*
X389150Y230300D03*
X407500Y84000D03*
X407400Y91000D03*
X411300Y85600D03*
X414722Y90250D03*
X418300Y91300D03*
X418400Y98150D03*
X411000Y92100D03*
X414622Y98000D03*
X404529Y118507D03*
X405900Y121700D03*
X409110Y114910D03*
X405200Y115343D03*
X412462Y115713D03*
X409196Y118195D03*
X416904Y119591D03*
X416922Y116613D03*
X413100Y121800D03*
X409110Y120910D03*
X404900Y124600D03*
X416000Y135983D03*
X415000Y131400D03*
X408956Y130064D03*
X418500Y128200D03*
X415100Y127900D03*
X406200Y127400D03*
X416851Y122600D03*
X412600Y124100D03*
X412462Y126300D03*
X404400Y128900D03*
X414900Y147000D03*
X417900Y146900D03*
X408800Y147000D03*
X411900Y146800D03*
X413300Y139100D03*
X413400Y142700D03*
X418000Y142500D03*
X415100Y149800D03*
X408837Y149809D03*
X418439Y167118D03*
X414800Y162600D03*
X411800Y162700D03*
X414572Y165913D03*
X411356Y165732D03*
X413314Y154908D03*
X410100Y157700D03*
X409300Y167163D03*
X407100Y167429D03*
X418600Y182800D03*
X414960Y178130D03*
X414950Y181460D03*
X411260Y178090D03*
X411553Y181222D03*
X416400Y170300D03*
X413265Y170423D03*
X410620Y173300D03*
X405100Y178500D03*
X416315Y183219D03*
X415992Y189254D03*
Y186205D03*
X419097Y189563D03*
X416500Y195563D03*
X408242Y184624D03*
X405231Y184976D03*
X408200Y190500D03*
X408100Y193600D03*
X412000Y187500D03*
X412500Y194900D03*
X412100Y190400D03*
X418800Y196700D03*
X416139Y192007D03*
X405102Y187874D03*
X412200Y192600D03*
X416900Y200100D03*
X408200Y226900D03*
X408100Y220500D03*
X404400Y228600D03*
Y222300D03*
X415600Y222700D03*
X415800Y215900D03*
X412050Y225100D03*
X412100Y218400D03*
X422078Y97678D03*
X422000Y91300D03*
X427560Y104770D03*
X429105Y106337D03*
X426800Y97850D03*
X429500Y93800D03*
X428100Y120000D03*
X424900Y121213D03*
X420600Y118300D03*
X420672Y120600D03*
X422042Y115224D03*
X424700Y115000D03*
X427900Y114300D03*
X428100Y116500D03*
X427500Y112091D03*
X425200Y118823D03*
X431188Y116105D03*
X430342Y119724D03*
X428255Y126236D03*
X425000Y135350D03*
X419500Y136400D03*
X430100Y131500D03*
X431700Y128300D03*
X423500Y128200D03*
X427000Y128050D03*
X423900Y131500D03*
X420942Y131324D03*
X422300Y126300D03*
X427600Y143841D03*
X421500Y142400D03*
X426900Y147100D03*
X431100Y145500D03*
X424856Y142270D03*
X422400Y139000D03*
X420861Y149687D03*
Y146923D03*
X430694Y142275D03*
X428390Y139059D03*
X423945Y165221D03*
X421710Y167230D03*
X431130Y166660D03*
X428238Y167709D03*
X420804Y162659D03*
X420900Y160037D03*
X425500Y154737D03*
X428400D03*
X434500Y160037D03*
X430360Y181350D03*
X430340Y177620D03*
X423642Y181374D03*
X426970Y178310D03*
X425400Y170240D03*
X428500Y173120D03*
X422337Y170575D03*
X425427Y173113D03*
X419453Y173187D03*
X420922Y178117D03*
X423842Y178274D03*
X428431Y170264D03*
X432100Y190400D03*
X429100Y189696D03*
X426173Y190784D03*
X428830Y195379D03*
X422152Y189600D03*
X420800Y193100D03*
X421171Y196496D03*
X431270Y193425D03*
X425500Y186045D03*
X423966Y190846D03*
X423800Y196500D03*
X433842Y197021D03*
X421848Y186550D03*
X428400Y185900D03*
X420975Y211300D03*
X427900Y202800D03*
X424832Y200174D03*
X421811Y202603D03*
X426311Y204399D03*
X419550Y222700D03*
X419600Y216200D03*
X437400Y121600D03*
X442842Y120824D03*
X438700Y112900D03*
X438500Y116400D03*
X439400Y120100D03*
X434960Y114529D03*
X444242Y124324D03*
X435442Y124024D03*
X437800Y128100D03*
X439275Y124197D03*
X443400Y148900D03*
X437472Y152501D03*
X434834Y163817D03*
X439600Y153800D03*
X438742Y197224D03*
X435642Y194824D03*
X437921Y192956D03*
X459800Y118800D03*
X453000Y118700D03*
X459700Y129900D03*
X452200Y129800D03*
X463100Y133700D03*
X456000Y133500D03*
X460100Y123100D03*
X453000Y123300D03*
X463200Y126200D03*
X456500Y126100D03*
X461200Y167400D03*
X454200D03*
X464300Y181800D03*
X458000Y171100D03*
X451000D03*
X460000Y174900D03*
X453000D03*
X457400Y197000D03*
X450400D03*
X462500Y189000D03*
X460400Y193300D03*
X453400D03*
X459500Y200700D03*
X452500D03*
X473900Y178200D03*
X466900D03*
X471300Y181800D03*
X473100Y185500D03*
X466000D03*
X469500Y189000D03*
X504000Y12507D03*
X508700Y14607D03*
X511589Y30295D03*
X507839Y30362D03*
X506496Y272500D03*
X523453Y12360D03*
X511800Y12507D03*
X520700Y14807D03*
X518769Y22907D03*
X515484D03*
X525753Y30893D03*
X522733Y32832D03*
X511640Y255956D03*
X514137Y256089D03*
X522908Y255117D03*
X526715Y254700D03*
X511736Y273001D03*
X514900Y271350D03*
X522992Y270700D03*
X525845Y272863D03*
X517846Y262489D03*
X521131D03*
X528525Y12549D03*
X542100Y15107D03*
X530700Y15407D03*
X536485Y22907D03*
X533200D03*
X542407Y30882D03*
X532350Y30807D03*
X529120Y32575D03*
X530015Y255000D03*
X531775Y252231D03*
X541005Y254800D03*
X530900Y273000D03*
X534100Y270700D03*
X541500Y270900D03*
X535562Y262489D03*
X538847D03*
X550000Y12507D03*
X544860Y12407D03*
X552800Y14807D03*
X557745Y22907D03*
X554460D03*
X553079Y30712D03*
X549500Y31607D03*
X545928Y31047D03*
X544800Y255100D03*
X550200Y255500D03*
X551000Y252056D03*
X544292Y273128D03*
X548800Y271000D03*
X551937Y272789D03*
X555641Y262489D03*
X568555Y12407D03*
X561200Y12507D03*
X571600Y14207D03*
X564400Y14307D03*
X570852Y33204D03*
X569800Y29807D03*
X565091Y30815D03*
X561456Y30902D03*
X561419Y254850D03*
X565054Y254773D03*
X568327Y253348D03*
X571867Y254685D03*
X560600Y270300D03*
X564100Y271100D03*
X567800Y270500D03*
X570200Y273100D03*
X558926Y262489D03*
X587940Y12417D03*
X582655Y12407D03*
X579800Y14807D03*
X577824Y22907D03*
X574539D03*
X585179Y30867D03*
X581450Y30707D03*
X587700Y255300D03*
X579205Y254850D03*
X582200Y252206D03*
X587642D03*
X580200Y273000D03*
X582600Y270300D03*
X588036Y273089D03*
X588400Y270300D03*
X573357Y262489D03*
X576642D03*
X594600Y6707D03*
X601704Y22907D03*
X594400Y36207D03*
X589300Y33007D03*
X594600Y260000D03*
X591300Y255010D03*
X590837Y259889D03*
X598398Y260199D03*
X591342Y252206D03*
X603187Y252056D03*
X589500Y257100D03*
X594500Y265200D03*
X591500Y270100D03*
X591536Y273000D03*
X590700Y264833D03*
X598300Y265400D03*
X589900Y268133D03*
X602450Y272900D03*
X598418Y262699D03*
X590322Y262361D03*
X594559Y262559D03*
X595386Y272932D03*
X610952Y12307D03*
X616600D03*
X614700Y14107D03*
X615852Y19807D03*
X615907Y24856D03*
X607300Y14507D03*
X616707Y15616D03*
X604989Y22907D03*
X615951Y22356D03*
X612000Y17407D03*
X610944Y33333D03*
X607800Y30407D03*
X618900Y33290D03*
X615103Y30690D03*
X615044Y33190D03*
X618877Y30790D03*
X619382Y260089D03*
X615532Y259700D03*
X611706Y259387D03*
X606700Y255600D03*
X604074Y254394D03*
X609500Y254900D03*
X609937Y252106D03*
X608700Y257300D03*
X611845Y253723D03*
X615537Y264789D03*
X619100Y265300D03*
X611536Y264385D03*
X609896Y272889D03*
X608996Y270206D03*
X605100Y270100D03*
X605065Y272967D03*
X611593Y261885D03*
X606200Y267800D03*
X615430Y262213D03*
X612393Y273026D03*
X619180Y262689D03*
X633500Y12406D03*
X624000D03*
X623532Y20007D03*
X623555Y25107D03*
X619607Y19807D03*
X627255Y25107D03*
X627231Y19907D03*
X630955Y25207D03*
X631000Y20107D03*
X634555Y25307D03*
X634757Y20207D03*
X619730Y24864D03*
X634757Y22707D03*
X623480Y22564D03*
X631007Y22707D03*
X619700Y22307D03*
X627257Y22407D03*
X624100Y33190D03*
X633449D03*
X630432Y260100D03*
X626682Y260300D03*
X622933Y260189D03*
X634207Y260300D03*
X630455Y265400D03*
X634280Y265332D03*
X626651Y265489D03*
X622899Y265189D03*
X629937Y272990D03*
X630457Y262832D03*
X626680Y262989D03*
X634280Y262832D03*
X620437Y272990D03*
X622930Y262689D03*
X644193Y12907D03*
X648800Y12707D03*
X641745Y12367D03*
X638400Y20607D03*
X638290Y25674D03*
X642246Y25807D03*
X642451Y20707D03*
X645300Y15507D03*
X648400Y15490D03*
X645200Y27707D03*
X646800Y17607D03*
X642257Y23307D03*
X638507Y23183D03*
X647000Y29607D03*
X649550Y30807D03*
X643700Y33290D03*
X644100Y30307D03*
X650200Y33307D03*
X641900Y31507D03*
X638032Y260342D03*
X642802Y252186D03*
X645920Y254130D03*
X635043Y252106D03*
X638900Y254809D03*
X635197Y254602D03*
X638893Y252206D03*
X638090Y265340D03*
X642937Y273089D03*
X646360Y271530D03*
X637288Y270100D03*
X637337Y272944D03*
X648948Y262489D03*
X637987Y262842D03*
X644550Y267170D03*
X639500Y268800D03*
X662359Y12379D03*
X657897Y12504D03*
X651316Y12360D03*
X659400Y25907D03*
Y20474D03*
X662192Y14874D03*
X663202Y25973D03*
X655602Y25223D03*
X663200Y20956D03*
X655700Y20225D03*
X664212Y16356D03*
X663300Y23454D03*
X662916Y28457D03*
X655592Y22723D03*
X659400Y23207D03*
X662503Y33207D03*
X657900Y30690D03*
X664678Y30307D03*
X661708Y30699D03*
X657900Y33190D03*
X659437Y246389D03*
X665500Y252189D03*
X659500Y274000D03*
X665100Y272700D03*
X652233Y262489D03*
X671290Y12457D03*
X665901Y12307D03*
X674320Y14219D03*
X666175Y14807D03*
X680580Y22807D03*
X677295D03*
X669600Y17907D03*
X674400Y31307D03*
X671295Y33190D03*
X670200Y254700D03*
X673770Y254752D03*
X669700Y270900D03*
X672800Y272700D03*
X676113Y262489D03*
X679398D03*
X690102Y12502D03*
X684760Y12256D03*
X692200Y15357D03*
X682013Y14848D03*
X695029Y22853D03*
X693300Y30607D03*
X689624Y30383D03*
X685700Y30807D03*
X681900Y30907D03*
X682800Y254900D03*
X685382Y252200D03*
X688800Y254600D03*
X692250Y255700D03*
X682481Y270700D03*
X685100Y273100D03*
X689700Y270800D03*
X692537Y272989D03*
X696192Y262489D03*
X709000Y12407D03*
X702000Y12607D03*
X705031Y14515D03*
X698277Y22855D03*
X708900Y30407D03*
X704430Y33313D03*
X701800Y30807D03*
X701649Y255049D03*
X704178Y252189D03*
X707800Y255000D03*
X711400Y255072D03*
X701300Y270777D03*
X704277Y272989D03*
X709400Y272600D03*
X699477Y262489D03*
X723586Y14080D03*
X712182Y14124D03*
X720100Y14707D03*
X718375Y22907D03*
X715090D03*
X727000Y30407D03*
X723500Y29907D03*
X721747Y32954D03*
X712400Y30807D03*
X721500Y255000D03*
X724374Y254515D03*
X712200Y270500D03*
X722400Y270800D03*
X725300Y272800D03*
X717452Y262489D03*
X720737D03*
X715900Y270000D03*
X742200Y12407D03*
X728010Y12857D03*
X739000Y14407D03*
X731169Y14584D03*
X736091Y23607D03*
X732806D03*
X742100Y33007D03*
X740200Y29907D03*
X730500D03*
X730400Y255400D03*
X732200Y252200D03*
X741560Y255000D03*
X730400Y272850D03*
X732740Y270200D03*
X741200Y270500D03*
X735168Y262489D03*
X738453D03*
X744900Y20500D03*
X745000Y23000D03*
X747441Y33007D03*
X744437Y252189D03*
X744200Y272600D03*
X753000Y272100D03*
G54D17*
X42717Y191732D03*
G54D19*
X144000Y67875D03*
Y147125D03*
X276811Y263386D03*
X296811D03*
X457913Y45276D03*
X477913D03*
G54D13*
X15400Y118000D03*
X10900D03*
X13000Y137000D03*
X15500Y122800D03*
X15000Y127500D03*
X11000Y122800D03*
X10500Y127500D03*
X13000Y141500D03*
X13100Y150600D03*
X13000Y146000D03*
X45500Y118000D03*
X63200Y194900D03*
X70900Y193800D03*
X122250Y228750D03*
Y233000D03*
Y237300D03*
Y241500D03*
X133941Y208863D03*
X131003Y205766D03*
X138100Y208100D03*
X136500Y272500D03*
X158700Y213800D03*
X315400Y110800D03*
X311600D03*
X322691Y136023D03*
X328000Y97100D03*
X334850Y96900D03*
X335500Y91600D03*
X339500Y102000D03*
X332600Y101400D03*
X333551Y115090D03*
X333416Y108899D03*
X341309Y135651D03*
X329693Y134428D03*
X331290Y125810D03*
X330870Y130540D03*
X344523Y98477D03*
X344500Y94000D03*
X347230Y100190D03*
X355175Y108212D03*
X348076Y108910D03*
X354333Y125665D03*
X343000Y124000D03*
X361141Y104099D03*
X369997Y113706D03*
X358000Y115500D03*
X367221Y125428D03*
X370000Y122563D03*
X367121Y128628D03*
X362111Y130128D03*
X369580Y215400D03*
X377818Y115008D03*
X377800Y124163D03*
X384650Y183170D03*
X380510Y185500D03*
X384684Y191950D03*
X376300Y213700D03*
X382471Y199843D03*
X385900Y222600D03*
X382700Y226000D03*
X379700Y216500D03*
X372950Y217400D03*
X396600Y112463D03*
X390683Y108042D03*
X400700Y108800D03*
X389200Y227400D03*
X392000Y217200D03*
X395700Y220600D03*
X399800D03*
X414672Y94500D03*
X417800Y100400D03*
X418300Y94800D03*
X407550Y100196D03*
X412100Y135600D03*
X417753Y131322D03*
X415700Y143100D03*
X410302Y141864D03*
X406042Y147025D03*
X407399Y142561D03*
X410272Y154794D03*
X416400Y155000D03*
X408200Y223800D03*
X412000Y222000D03*
X404400Y225300D03*
X422050Y94800D03*
X430302Y112098D03*
X419596Y113463D03*
X431504Y126061D03*
X424982Y126500D03*
X432542Y136898D03*
X426982Y131334D03*
X423496Y144000D03*
X428363Y141756D03*
X426000Y167370D03*
X430542Y160753D03*
X430600Y164513D03*
X422363Y154700D03*
X444578Y106201D03*
X442378Y106198D03*
X440178Y106200D03*
X443443Y144757D03*
X437398Y146257D03*
X435004Y142110D03*
G54D23*
X305900Y121151D03*
X311200Y114800D03*
X311410Y118110D03*
X312000Y122600D03*
X312917Y133440D03*
G54D14*
X14500Y198000D03*
X17301Y212401D03*
X4500Y228900D03*
X4600Y223100D03*
X17300Y218307D03*
X10000Y229500D03*
X16400Y224212D03*
X4500Y234800D03*
X4400Y245100D03*
X16118Y230118D03*
X10194Y243106D03*
X9500Y234200D03*
X16899Y241929D03*
X16300Y236023D03*
X4400Y256700D03*
X10190Y258510D03*
X10194Y254917D03*
X10190Y246699D03*
X16899Y247834D03*
Y253740D03*
Y259645D03*
X5000Y275000D03*
X12600Y266900D03*
X7600Y268100D03*
X16899Y265551D03*
X15300Y285800D03*
X4900Y285700D03*
X32800Y120400D03*
X25800Y120300D03*
X29200D03*
X30000Y196200D03*
X21900Y205400D03*
X31500Y207500D03*
X25200Y286000D03*
X40500Y127700D03*
X38500Y148000D03*
X48500D03*
X41000Y152300D03*
Y143300D03*
X46000D03*
Y152300D03*
X43500Y148000D03*
Y138500D03*
X48500D03*
X38500D03*
X45800Y158100D03*
X34800Y198800D03*
Y203700D03*
X37600Y212700D03*
Y207800D03*
X34500Y216000D03*
X40400Y217100D03*
X40700Y224000D03*
X40200Y238300D03*
Y231300D03*
Y245300D03*
X40500Y260000D03*
X40600Y252500D03*
X63500Y43500D03*
Y57500D03*
Y48000D03*
Y52500D03*
X52500Y96500D03*
Y106500D03*
X57500Y96500D03*
X60000Y101500D03*
X50000D03*
X55000D03*
X57500Y106500D03*
X60000Y111300D03*
X50000D03*
X55000D03*
X50500Y160000D03*
X54700Y192200D03*
X52700Y184800D03*
X62800Y184300D03*
X57600Y214200D03*
X74000Y37642D03*
X66500D03*
X68500Y47500D03*
X73500Y48000D03*
X68000Y52500D03*
X72137Y210237D03*
X79500Y230000D03*
X78700Y259800D03*
X67600Y255800D03*
X66300Y259300D03*
X67000Y263200D03*
X82211Y37747D03*
X89862Y37849D03*
X95500Y93500D03*
X94000Y137500D03*
Y133000D03*
X84500Y230000D03*
X89500D03*
X84500Y225000D03*
Y235000D03*
X91400Y270300D03*
X98500Y37642D03*
X105794Y37692D03*
X99500Y91500D03*
Y96000D03*
X104000Y106600D03*
Y92000D03*
Y96500D03*
Y115500D03*
Y111000D03*
X105775Y137349D03*
X103175Y134050D03*
X98500Y137500D03*
X109000Y134050D03*
X98500Y133000D03*
X95700Y197200D03*
X99600Y225700D03*
X99328Y235370D03*
X109000Y231400D03*
X113605Y37665D03*
X121500Y37642D03*
X119400Y106700D03*
X123800Y102500D03*
X123900Y106700D03*
X119400Y102300D03*
Y115900D03*
Y111200D03*
X123900Y115900D03*
Y111200D03*
X114500Y134050D03*
X120500Y139000D03*
X125000Y178000D03*
X119760Y191419D03*
X115760D03*
X123760D03*
X129336Y37652D03*
X137300Y37642D03*
X136770Y113000D03*
X136500Y126300D03*
X153088Y37653D03*
X145070Y37642D03*
X147400Y60400D03*
X157175Y115462D03*
X150670Y112100D03*
Y122300D03*
X150500Y183000D03*
X168791Y37689D03*
X160898Y37704D03*
X158105Y96775D03*
X171800Y126600D03*
X162900Y152200D03*
X158500Y161820D03*
X167602Y160684D03*
X165700Y203400D03*
X162000Y226000D03*
X167000D03*
Y221500D03*
X162000D03*
Y230500D03*
X167000D03*
X162000Y235000D03*
X176640Y37699D03*
X184500Y37700D03*
X174900Y77700D03*
X177200Y130575D03*
X187597Y133697D03*
X176400Y175700D03*
X185546Y192509D03*
X180546D03*
X175546D03*
X177500Y209500D03*
X176800Y241600D03*
X186500Y276500D03*
Y281000D03*
X192400Y37642D03*
X200300D03*
X202500Y97000D03*
X188363Y116137D03*
X201252Y137766D03*
X192237Y147300D03*
X201200Y164200D03*
X199600Y160100D03*
X199900Y154200D03*
X200900Y177000D03*
X202800Y191400D03*
X196000Y186897D03*
X191400Y206100D03*
X203100Y252900D03*
X191100Y276600D03*
X190900Y280800D03*
X207600Y37642D03*
X216085Y37649D03*
X213558Y98500D03*
X205689Y112879D03*
X205850Y118175D03*
X210100Y135800D03*
X212300Y157300D03*
X212600Y161500D03*
X213850Y179850D03*
X205920Y221550D03*
X211900Y253000D03*
X207500D03*
X212400Y281200D03*
X217000Y281000D03*
X212500Y277000D03*
X208000D03*
X223868Y37686D03*
X231780Y37691D03*
X231562Y143827D03*
X231611Y138336D03*
X226452Y147300D03*
X233350Y180700D03*
X232225Y193275D03*
X234525Y239250D03*
X229700Y234700D03*
X225300Y239200D03*
X234525Y243450D03*
X229725D03*
X225300Y243400D03*
X234525Y234800D03*
X225300D03*
X229675Y239000D03*
X233500Y258958D03*
X228000Y259000D03*
X239599Y37673D03*
X247500Y37642D03*
X240297Y63400D03*
X244463Y130655D03*
X242950Y155800D03*
X236477Y179357D03*
X239300Y196800D03*
X236861Y184967D03*
X247500Y239250D03*
X243300Y235050D03*
X247500Y243450D03*
X243300D03*
X238900D03*
X243300Y239250D03*
X247500Y235050D03*
X238925Y235000D03*
Y239200D03*
X248000Y259000D03*
X238500D03*
X243000D03*
X255000Y37642D03*
X263100Y37700D03*
X264189Y98252D03*
X251700Y239250D03*
Y243450D03*
X252500Y259000D03*
X271000Y37800D03*
X278800Y37700D03*
X268928Y112625D03*
X268895Y107350D03*
X268300Y141869D03*
X286900Y37800D03*
X294500Y37900D03*
X285100Y129510D03*
X281500Y142100D03*
X295900Y154200D03*
X285000Y261700D03*
X310348Y37900D03*
X302600Y37800D03*
X311000Y141731D03*
X297250Y163700D03*
X311242Y158732D03*
X326096Y37900D03*
X318048Y37700D03*
X325350Y114500D03*
X326313Y122380D03*
X322000Y264300D03*
X333700Y38000D03*
X330470Y112515D03*
X330910Y115010D03*
X353500Y71900D03*
X357000Y69500D03*
X349300Y83000D03*
X345100D03*
X354200Y76400D03*
X346600Y121100D03*
X371400Y42500D03*
X363583Y37642D03*
X371500Y47000D03*
X359800Y72700D03*
X362700Y69600D03*
X368721Y108528D03*
X365721Y115528D03*
X366400Y112200D03*
X369500Y237200D03*
Y240600D03*
Y234600D03*
Y244000D03*
X365800Y264900D03*
X362400D03*
X369300D03*
X380000Y38100D03*
X375600Y42500D03*
X380300D03*
X375400Y37700D03*
X375700Y47000D03*
X380295Y46779D03*
X380000Y263461D03*
X383500D03*
X376500D03*
X393198Y158940D03*
X399298Y162090D03*
X402505Y159133D03*
X396148Y158940D03*
X399298D03*
X393000Y236200D03*
X397400Y239700D03*
X389500Y275300D03*
X405990Y144251D03*
X409096Y143963D03*
X412900Y157800D03*
X411600Y159600D03*
X408900Y162463D03*
X410408Y170261D03*
X407552Y170424D03*
X415700Y219200D03*
X405700Y246500D03*
X430500Y17000D03*
X426900Y160040D03*
X419340Y170500D03*
X434482Y177021D03*
X419600Y219200D03*
X423900Y257500D03*
X444783Y28451D03*
X434700Y128200D03*
X439276Y159645D03*
X443800Y246100D03*
X445300Y274400D03*
X451000Y257413D03*
X456300Y275300D03*
X474000Y9000D03*
X467200Y4400D03*
X480400Y154050D03*
X467100Y154200D03*
X477000Y154050D03*
X470100Y154200D03*
X473500Y154050D03*
X467700Y245500D03*
X481500Y8900D03*
X489600Y8800D03*
X483800Y154050D03*
X487200Y154100D03*
X497100Y8800D03*
X506800Y12907D03*
X508700Y17207D03*
X506500Y32807D03*
X502000Y89000D03*
X511200Y183400D03*
X500900D03*
X505200Y215000D03*
X514360Y12417D03*
X526000Y12507D03*
X519426Y12318D03*
X522311Y16720D03*
X514300Y20507D03*
X519623Y20457D03*
X522700Y30007D03*
X513005Y32412D03*
X519400Y33340D03*
X526700Y33207D03*
X525740Y88960D03*
X524700Y119500D03*
X515000Y119270D03*
X524700Y145041D03*
X526600Y183500D03*
X513100Y234500D03*
X516500D03*
X537964Y12317D03*
X532500Y13407D03*
X541114Y12307D03*
X528219Y15096D03*
X532472Y20515D03*
X537410Y20584D03*
X529000Y30007D03*
X541950Y33340D03*
X532542Y33307D03*
X537200Y33207D03*
X531500Y219500D03*
X541500Y234900D03*
X547500Y12507D03*
X553720Y12297D03*
X550234Y14997D03*
X553797Y20496D03*
X549500Y29107D03*
X553250Y33207D03*
X547306Y33134D03*
X551800Y69600D03*
X548400Y69700D03*
X555199D03*
X556500Y89000D03*
X546349Y89512D03*
X552100Y136000D03*
X557100D03*
X544954Y183600D03*
X551700Y209800D03*
X550400Y222285D03*
X558448Y12407D03*
X566040Y12317D03*
X566000Y16507D03*
X572200Y28707D03*
X558500Y20507D03*
X573200Y19907D03*
X565470Y33287D03*
X573242Y32462D03*
X560635Y33264D03*
X561999Y69700D03*
X558599D03*
X570715Y89100D03*
X572100Y136000D03*
X567100D03*
X562000Y127800D03*
X562100Y136000D03*
X562000Y144900D03*
X558915Y183603D03*
X569200Y223600D03*
X573470Y12347D03*
X578620Y12357D03*
X585280Y12267D03*
X583700Y28207D03*
X578600Y20307D03*
X579100Y33207D03*
X585550Y33340D03*
X582254Y183313D03*
X590000Y14007D03*
X594500Y4007D03*
X600896Y12407D03*
X601000Y20507D03*
X590500Y30507D03*
X594200Y33607D03*
X600360Y33287D03*
X596845Y89624D03*
X599300Y119270D03*
X588800Y145000D03*
X599200D03*
X590975Y183275D03*
X588800Y205900D03*
X603964Y210400D03*
X600900Y230200D03*
X605700Y12407D03*
X610800Y14807D03*
X605728Y20518D03*
X610500Y30507D03*
X607544Y33340D03*
X617700Y125500D03*
X615700Y230200D03*
X630000Y55300D03*
X627500Y104900D03*
X620000Y112575D03*
X623400Y230100D03*
X640500Y55000D03*
X639500Y136490D03*
X648500Y162600D03*
X655133Y55833D03*
X653000Y93000D03*
X650726Y125724D03*
X664212Y147993D03*
X661600Y156700D03*
X654100Y221800D03*
X675990Y12357D03*
X676600Y20307D03*
X671500Y15007D03*
X671900Y30707D03*
X675970Y33267D03*
X678400Y114500D03*
X668411Y148089D03*
X678500Y141500D03*
X667061Y175239D03*
X676200Y181600D03*
X687602Y12439D03*
X694200Y13507D03*
X681280Y12457D03*
X684500Y15507D03*
X689595Y27883D03*
X685400Y28307D03*
X681700Y20507D03*
X694205Y20302D03*
X693700Y33107D03*
X681280Y33340D03*
X687900Y33327D03*
X693500Y148000D03*
X690000Y159000D03*
X694500D03*
X684700Y179800D03*
X694600Y229800D03*
X699503Y12482D03*
X706360Y12397D03*
X705604Y16949D03*
X710813Y28796D03*
X699104Y20495D03*
X707157Y33333D03*
X700940Y33340D03*
X700089Y91411D03*
X701600Y104900D03*
X701400Y98400D03*
X698000Y181500D03*
X704700Y183800D03*
X710200Y201700D03*
X714000Y12407D03*
X719110Y12347D03*
X725530Y12507D03*
X714100Y20607D03*
X719220Y20553D03*
X721074Y30514D03*
X718350Y33107D03*
X712450Y33340D03*
X725653Y32654D03*
X725632Y49600D03*
X721950Y51950D03*
X722000Y74500D03*
X717000D03*
X715000Y80300D03*
X714500Y85500D03*
X715700Y124200D03*
X727187Y140000D03*
X717000Y187500D03*
X715500Y205837D03*
X737300Y12307D03*
X732110Y12267D03*
X728500Y15507D03*
X742100Y28107D03*
X732000Y20307D03*
X736748D03*
X728500Y27907D03*
X733474Y33340D03*
X738487Y33094D03*
X739500Y75500D03*
X738000Y65700D03*
X738500Y90000D03*
X731340Y82515D03*
X739500Y114900D03*
X741104Y133763D03*
X736900Y162300D03*
X729500D03*
X733400D03*
X737000Y188315D03*
X734000Y205000D03*
X745100Y12256D03*
X744800Y33007D03*
X752500Y49007D03*
X756000Y106000D03*
X758176Y135024D03*
X745104Y129763D03*
X749104Y133763D03*
X745104D03*
X752191Y146613D03*
X745104Y137763D03*
X747000Y162000D03*
X750500D03*
X746000Y182300D03*
X764500Y84800D03*
X760400Y88700D03*
X768100Y89000D03*
X761300Y95700D03*
X768500Y114000D03*
X763600Y168000D03*
X764000Y188000D03*
Y197500D03*
Y192810D03*
Y202310D03*
X769500Y234500D03*
X769400Y252700D03*
X785500Y8000D03*
X784000Y31000D03*
X781500Y51000D03*
X777000Y93100D03*
X774300Y102500D03*
X778500D03*
Y107000D03*
X774300D03*
X783000Y113000D03*
Y118500D03*
Y123000D03*
X779000Y142000D03*
X788515Y144060D03*
X784515D03*
X796515D03*
X792515D03*
X800515D03*
Y148060D03*
X796515D03*
X792515D03*
X810500Y196500D03*
Y192300D03*
X809200Y209500D03*
Y213700D03*
Y218400D03*
X809100Y228600D03*
Y224400D03*
X808700Y238300D03*
Y234100D03*
Y242900D03*
X809500Y251500D03*
Y257000D03*
X808700Y247100D03*
X809700Y285900D03*
X820500Y6500D03*
X821900Y273100D03*
X821600Y285500D03*
G54D29*
X350197Y231103D03*
G54D11*
X11500Y68500D03*
X12000Y279000D03*
X816000Y280000D03*
G54D16*
X45669Y77185D03*
Y172460D03*
G54D21*
X200197Y282677D03*
X298622D03*
G54D10*
X-19686Y15748D03*
Y573228D03*
X846455Y15748D03*
Y573228D03*
G54D25*
X315613Y100850D03*
X339280Y127380D03*
X434700Y131800D03*
G54D26*
X325300Y112300D03*
X319252Y140949D03*
X311417Y153821D03*
X385750Y128517D03*
X380400Y133928D03*
X399452Y133964D03*
X389380Y130100D03*
X393000Y152663D03*
X402900Y149663D03*
X393000Y140268D03*
X403132Y144374D03*
X403080Y146931D03*
X399198Y146468D03*
X396192Y146444D03*
X392998Y149718D03*
X399198Y149618D03*
X396182Y149674D03*
X396200Y152763D03*
X396300Y162100D03*
X399300Y152863D03*
Y155963D03*
X403078Y152922D03*
X405500Y131063D03*
X406000Y150200D03*
X407500Y152100D03*
X410400Y152000D03*
X407500Y157600D03*
X407400Y154863D03*
X406100Y159500D03*
X417900Y178363D03*
X431620Y154620D03*
X421697Y174049D03*
X456200Y118900D03*
Y129600D03*
X459700Y133600D03*
X459800Y126200D03*
X456500Y123000D03*
X457700Y167400D03*
X456500Y174900D03*
X454500Y171100D03*
X456900Y193300D03*
X453900Y197000D03*
X456000Y200700D03*
X470400Y178200D03*
X467800Y181800D03*
X469600Y185500D03*
X466000Y189000D03*
G54D27*
X322010Y118573D03*
X323007Y127672D03*
X349600Y126700D03*
X371900Y89000D03*
X368600Y94100D03*
X365000Y94700D03*
X357721Y95100D03*
X360900Y94200D03*
X359942Y110924D03*
X375800Y87000D03*
X383450Y86900D03*
X387200D03*
X379500D03*
X379526Y106396D03*
X381950Y100950D03*
X381550Y117400D03*
X377800Y112063D03*
X386561Y108812D03*
X377713Y121061D03*
X397300Y93100D03*
X390650Y93000D03*
X394100Y94900D03*
X400400Y95000D03*
X393028Y162059D03*
X402373Y155952D03*
X396000Y179000D03*
X414300Y85600D03*
X403800Y87000D03*
X407400Y87400D03*
X411000Y88900D03*
X417785Y162622D03*
X415100Y158100D03*
X408600Y159600D03*
X406000Y162663D03*
X404558Y154835D03*
X408158Y178666D03*
X411342Y185024D03*
X419499Y139064D03*
X423910Y175700D03*
X432712Y172469D03*
X435453Y167560D03*
X435105Y181207D03*
X435453Y185397D03*
X507817Y252248D03*
X511200Y258900D03*
X509244Y272796D03*
X516600Y252200D03*
X521800Y252875D03*
X513776Y258563D03*
X516727Y273122D03*
X521790Y273140D03*
X517100Y265100D03*
X521987D03*
X532900Y255300D03*
X535098Y252600D03*
X540900Y252300D03*
X527400Y252100D03*
X529300Y271000D03*
X528330Y273140D03*
X539937Y272989D03*
X539505Y265100D03*
X534905Y273097D03*
X534700Y265100D03*
X552800Y255300D03*
X545500Y252600D03*
X553485Y252332D03*
X546200Y271000D03*
X554500Y264900D03*
X546900Y273100D03*
X554434Y272914D03*
X560555Y252503D03*
X563376Y256627D03*
X566151Y252115D03*
X572150Y252200D03*
X570200Y269700D03*
X559600Y272900D03*
X572155Y264900D03*
X565700Y273050D03*
X559700Y264900D03*
X572700Y273100D03*
X582300Y254900D03*
X578800Y252200D03*
X577450Y264900D03*
X580107Y270501D03*
X577636Y272947D03*
X643020Y254710D03*
X647800Y252300D03*
X644090Y270420D03*
X648200Y265300D03*
X648291Y273140D03*
X665300Y254700D03*
X661200Y248500D03*
X653600Y252130D03*
X664500Y270000D03*
X653000Y264900D03*
X661600Y272300D03*
X653041Y272989D03*
X669930Y252150D03*
X674636Y252406D03*
X680600Y265000D03*
X675400D03*
X668000Y272890D03*
X680400Y273100D03*
X675400D03*
X690000Y256800D03*
X685390Y254900D03*
X688720Y252090D03*
X693860Y252210D03*
X681900Y252500D03*
X691900Y269300D03*
X683100Y268000D03*
X695500Y265000D03*
Y273100D03*
X687682Y272889D03*
X704137Y254796D03*
X699800Y252230D03*
X701704Y257549D03*
X707490Y252310D03*
X706000Y270500D03*
X700200Y264900D03*
X700300Y273100D03*
X706900Y273000D03*
X712350Y252640D03*
X725950Y252573D03*
X721395Y252175D03*
X721600Y257500D03*
X716737Y252189D03*
X716795Y265000D03*
X721400D03*
X721395Y273100D03*
X713100Y273000D03*
X716737Y272989D03*
X730300Y257900D03*
X734937Y253100D03*
X739750Y252800D03*
X729860Y269810D03*
X734200Y265100D03*
X739111Y264962D03*
X739838Y272813D03*
X727800Y272800D03*
X734510Y273110D03*
X744100Y254800D03*
X749000Y252200D03*
X746737Y272889D03*
G54D28*
X320321Y130528D03*
X351342Y114158D03*
X351000Y111700D03*
X412500Y197300D03*
X405000Y190700D03*
X405800Y196700D03*
X416353Y207249D03*
X421253Y199822D03*
X425642Y209524D03*
X445000Y194500D03*
X443100Y195900D03*
X443000Y192700D03*
X436957Y209867D03*
G54D30*
X384810Y208530D03*
X384644Y205994D03*
X392382Y102149D03*
X400400Y209400D03*
X398500Y208000D03*
X412650Y100197D03*
X434021Y100128D03*
X429933Y197283D03*
%LPC*%
G75*
G54D31*
G01X10636Y-27865D02*
G02I-12000J0D01*
G01X14636D02*
X-17364D01*
G01X5486D02*
G02I-6850J0D01*
G01X-1364Y-43865D02*
Y-11865D01*
G01X14636Y-43865D02*
Y-123865D01*
G01D02*
X1309236D01*
G01X14636Y-79365D02*
X1309236D01*
G01X14636Y-43865D02*
X1309236D01*
G01X521736D02*
Y-123865D01*
G01X659236Y-43865D02*
Y-123865D01*
G01X774236Y-43865D02*
Y-123865D01*
G01X941736Y-43865D02*
Y-123865D01*
G01X1111736Y-43865D02*
Y-123865D01*
G01X1309236Y-43865D02*
Y-123865D01*
G01X1341236Y-27865D02*
X1309236D01*
G01X1337236D02*
G02I-12000J0D01*
G01X1332086D02*
G02I-6850J0D01*
G01X1325236Y-43865D02*
Y-11865D01*
G54D32*
G01X70851Y-113865D02*
Y-96365D01*
G01X80021D02*
Y-113865D01*
G01Y-105115D02*
X70851D01*
G01X92936Y-113865D02*
X91626Y-113573D01*
X90316Y-112407D01*
X89442Y-110365D01*
X89006Y-108032D01*
X89442Y-105698D01*
X90316Y-103657D01*
X91626Y-102490D01*
X92936Y-102199D01*
X94246Y-102490D01*
X95556Y-103657D01*
X96429Y-105698D01*
X96648Y-108032D01*
X96429Y-110365D01*
X95556Y-112407D01*
X94246Y-113573D01*
X92936Y-113865D01*
G01X106724D02*
Y-102199D01*
G01Y-105115D02*
X107598Y-103657D01*
X108908Y-102490D01*
X110654Y-102199D01*
X112182Y-102490D01*
X113493Y-103657D01*
X114148Y-105698D01*
Y-113865D01*
G01X124661Y-105990D02*
X131648D01*
X130993Y-103948D01*
X129901Y-102782D01*
X128373Y-102199D01*
X126844Y-102490D01*
X125534Y-103365D01*
X124661Y-105407D01*
X124224Y-107157D01*
Y-108907D01*
X124661Y-110657D01*
X125753Y-112407D01*
X127063Y-113573D01*
X128591Y-113865D01*
X130119Y-113282D01*
X131648Y-111532D01*
G01X140851Y-119115D02*
X142161Y-119698D01*
X143908Y-119115D01*
X144999Y-117949D01*
X145873Y-116490D01*
X147182Y-111824D01*
X150021Y-102199D01*
G01X143034D02*
X147182Y-111824D01*
G01X182182Y-104532D02*
X183056Y-103657D01*
X183711Y-102199D01*
X184148Y-100156D01*
X183711Y-98407D01*
X182838Y-97240D01*
X181309Y-96365D01*
X175414D01*
Y-113865D01*
X182619D01*
X184148Y-112699D01*
X185021Y-110948D01*
X185458Y-108907D01*
X185021Y-106865D01*
X183711Y-105115D01*
X182182Y-104532D01*
X175414D01*
G01X201866Y-113865D02*
Y-102199D01*
G01Y-104240D02*
X200993Y-103074D01*
X199682Y-102490D01*
X198154Y-102199D01*
X196626Y-102782D01*
X195316Y-103948D01*
X194442Y-105698D01*
X194006Y-108032D01*
X194442Y-110365D01*
X195316Y-112115D01*
X196626Y-113282D01*
X198154Y-113865D01*
X199682Y-113573D01*
X200993Y-112699D01*
X201866Y-111532D01*
G01X219366Y-96365D02*
Y-113865D01*
G01Y-111241D02*
X218493Y-112699D01*
X217182Y-113573D01*
X215654Y-113865D01*
X213908Y-113282D01*
X212598Y-111824D01*
X211724Y-110074D01*
X211506Y-108032D01*
X211724Y-105990D01*
X212598Y-104240D01*
X213908Y-102782D01*
X215654Y-102199D01*
X217182Y-102490D01*
X218274Y-103074D01*
X219366Y-104240D01*
G01X229879Y-118240D02*
X231408Y-119407D01*
X233154Y-119698D01*
X234682Y-119407D01*
X235993Y-117949D01*
X236866Y-115907D01*
Y-102199D01*
G01Y-104532D02*
X235993Y-103365D01*
X234682Y-102490D01*
X233154Y-102199D01*
X231408Y-102782D01*
X230316Y-103948D01*
X229442Y-105990D01*
X229006Y-108032D01*
X229224Y-109782D01*
X230098Y-111824D01*
X231408Y-113282D01*
X233154Y-113865D01*
X234464Y-113573D01*
X235993Y-112407D01*
X236866Y-111241D01*
G01X247161Y-105990D02*
X254148D01*
X253493Y-103948D01*
X252401Y-102782D01*
X250873Y-102199D01*
X249344Y-102490D01*
X248034Y-103365D01*
X247161Y-105407D01*
X246724Y-107157D01*
Y-108907D01*
X247161Y-110657D01*
X248253Y-112407D01*
X249563Y-113573D01*
X251091Y-113865D01*
X252619Y-113282D01*
X254148Y-111532D01*
G01X264879Y-113865D02*
Y-102199D01*
G01Y-104532D02*
X265971Y-103365D01*
X267063Y-102490D01*
X268591Y-102199D01*
X269682Y-102490D01*
X270993Y-103365D01*
G01X298569Y-113865D02*
Y-96365D01*
X303809D01*
X305556Y-97240D01*
X306866Y-99282D01*
X307303Y-101615D01*
X306866Y-103948D01*
X305774Y-105698D01*
X303809Y-106574D01*
X298569D01*
G01X324366Y-113865D02*
Y-102199D01*
G01Y-104240D02*
X323493Y-103074D01*
X322182Y-102490D01*
X320654Y-102199D01*
X319126Y-102782D01*
X317816Y-103948D01*
X316942Y-105698D01*
X316506Y-108032D01*
X316942Y-110365D01*
X317816Y-112115D01*
X319126Y-113282D01*
X320654Y-113865D01*
X322182Y-113573D01*
X323493Y-112699D01*
X324366Y-111532D01*
G01X334224Y-113865D02*
Y-102199D01*
G01Y-105115D02*
X335098Y-103657D01*
X336408Y-102490D01*
X338154Y-102199D01*
X339682Y-102490D01*
X340993Y-103657D01*
X341648Y-105698D01*
Y-113865D01*
G01X355436Y-96365D02*
Y-113865D01*
G01X352379Y-102199D02*
X358493D01*
G01X369224Y-113865D02*
Y-96365D01*
G01Y-104823D02*
X370316Y-103365D01*
X371408Y-102490D01*
X373154Y-102199D01*
X374464Y-102490D01*
X375993Y-103657D01*
X376648Y-105407D01*
Y-113865D01*
G01X387161Y-105990D02*
X394148D01*
X393493Y-103948D01*
X392401Y-102782D01*
X390873Y-102199D01*
X389344Y-102490D01*
X388034Y-103365D01*
X387161Y-105407D01*
X386724Y-107157D01*
Y-108907D01*
X387161Y-110657D01*
X388253Y-112407D01*
X389563Y-113573D01*
X391091Y-113865D01*
X392619Y-113282D01*
X394148Y-111532D01*
G01X404879Y-113865D02*
Y-102199D01*
G01Y-104532D02*
X405971Y-103365D01*
X407063Y-102490D01*
X408591Y-102199D01*
X409682Y-102490D01*
X410993Y-103365D01*
G01X437259Y-113865D02*
Y-96365D01*
X442936Y-110948D01*
X448613Y-96365D01*
Y-113865D01*
G01X462182Y-104532D02*
X463056Y-103657D01*
X463711Y-102199D01*
X464148Y-100156D01*
X463711Y-98407D01*
X462838Y-97240D01*
X461309Y-96365D01*
X455414D01*
Y-113865D01*
X462619D01*
X464148Y-112699D01*
X465021Y-110948D01*
X465458Y-108907D01*
X465021Y-106865D01*
X463711Y-105115D01*
X462182Y-104532D01*
X455414D01*
G01X227259Y-68865D02*
Y-51365D01*
X232936Y-65948D01*
X238613Y-51365D01*
Y-68865D01*
G01X250436D02*
X249126Y-68573D01*
X247816Y-67407D01*
X246942Y-65365D01*
X246506Y-63032D01*
X246942Y-60698D01*
X247816Y-58657D01*
X249126Y-57490D01*
X250436Y-57199D01*
X251746Y-57490D01*
X253056Y-58657D01*
X253929Y-60698D01*
X254148Y-63032D01*
X253929Y-65365D01*
X253056Y-67407D01*
X251746Y-68573D01*
X250436Y-68865D01*
G01X271866Y-51365D02*
Y-68865D01*
G01Y-66241D02*
X270993Y-67699D01*
X269682Y-68573D01*
X268154Y-68865D01*
X266408Y-68282D01*
X265098Y-66824D01*
X264224Y-65074D01*
X264006Y-63032D01*
X264224Y-60990D01*
X265098Y-59240D01*
X266408Y-57782D01*
X268154Y-57199D01*
X269682Y-57490D01*
X270774Y-58074D01*
X271866Y-59240D01*
G01X282161Y-60990D02*
X289148D01*
X288493Y-58948D01*
X287401Y-57782D01*
X285873Y-57199D01*
X284344Y-57490D01*
X283034Y-58365D01*
X282161Y-60407D01*
X281724Y-62157D01*
Y-63907D01*
X282161Y-65657D01*
X283253Y-67407D01*
X284563Y-68573D01*
X286091Y-68865D01*
X287619Y-68282D01*
X289148Y-66532D01*
G01X302936Y-68865D02*
Y-51365D01*
G01X542319Y-68865D02*
Y-51365D01*
X547559D01*
X549306Y-52240D01*
X550616Y-54282D01*
X551053Y-56615D01*
X550616Y-58948D01*
X549524Y-60698D01*
X547559Y-61574D01*
X542319D01*
G01X568989Y-52824D02*
X567679Y-51948D01*
X566151Y-51365D01*
X564404D01*
X562439Y-52240D01*
X560911Y-53698D01*
X559819Y-55449D01*
X558946Y-58365D01*
X558727Y-60990D01*
X559164Y-63615D01*
X559819Y-65365D01*
X561129Y-67115D01*
X562658Y-68282D01*
X564186Y-68865D01*
X565714D01*
X567243Y-68282D01*
X568553Y-67407D01*
X569645Y-66241D01*
G01X583432Y-59532D02*
X584306Y-58657D01*
X584961Y-57199D01*
X585398Y-55156D01*
X584961Y-53407D01*
X584088Y-52240D01*
X582559Y-51365D01*
X576664D01*
Y-68865D01*
X583869D01*
X585398Y-67699D01*
X586271Y-65948D01*
X586708Y-63907D01*
X586271Y-61865D01*
X584961Y-60115D01*
X583432Y-59532D01*
X576664D01*
G01X592636Y-74698D02*
X605736D01*
G01X611664Y-68865D02*
Y-51365D01*
X621708Y-68865D01*
Y-51365D01*
G01X634186Y-68865D02*
X632439Y-68573D01*
X630911Y-67407D01*
X629601Y-65657D01*
X628727Y-63615D01*
X628291Y-61282D01*
Y-58948D01*
X628727Y-56615D01*
X629601Y-54573D01*
X630911Y-52824D01*
X632439Y-51657D01*
X634186Y-51365D01*
X635932Y-51657D01*
X637461Y-52824D01*
X638771Y-54573D01*
X639645Y-56615D01*
X640081Y-58948D01*
Y-61282D01*
X639645Y-63615D01*
X638771Y-65657D01*
X637461Y-67407D01*
X635932Y-68573D01*
X634186Y-68865D01*
G01X555436Y-113865D02*
Y-96365D01*
X552816Y-99865D01*
G01Y-113865D02*
X558056D01*
G01X568133Y-110365D02*
X569442Y-112407D01*
X571189Y-113573D01*
X573154Y-113865D01*
X574901Y-113573D01*
X576648Y-112115D01*
X577739Y-110365D01*
X577958Y-108615D01*
X577521Y-106574D01*
X575993Y-105115D01*
X574464Y-104532D01*
X572499D01*
G01X574464D02*
X575774Y-103657D01*
X576866Y-102199D01*
X577303Y-100449D01*
X576866Y-98698D01*
X575774Y-97240D01*
X573809Y-96365D01*
X571844Y-96657D01*
X569879Y-97824D01*
G01X590436Y-113865D02*
Y-96365D01*
X587816Y-99865D01*
G01Y-113865D02*
X593056D01*
G01X603133Y-110365D02*
X604442Y-112407D01*
X606189Y-113573D01*
X608154Y-113865D01*
X609901Y-113573D01*
X611648Y-112115D01*
X612739Y-110365D01*
X612958Y-108615D01*
X612521Y-106574D01*
X610993Y-105115D01*
X609464Y-104532D01*
X607499D01*
G01X609464D02*
X610774Y-103657D01*
X611866Y-102199D01*
X612303Y-100449D01*
X611866Y-98698D01*
X610774Y-97240D01*
X608809Y-96365D01*
X606844Y-96657D01*
X604879Y-97824D01*
G01X625436Y-96365D02*
X623689Y-96948D01*
X622379Y-98407D01*
X621506Y-100156D01*
X620851Y-102490D01*
X620633Y-105115D01*
X620851Y-107740D01*
X621506Y-110074D01*
X622379Y-111824D01*
X623689Y-113282D01*
X625436Y-113865D01*
X627182Y-113282D01*
X628493Y-111824D01*
X629366Y-110074D01*
X630021Y-107740D01*
X630239Y-105115D01*
X630021Y-102490D01*
X629366Y-100156D01*
X628493Y-98407D01*
X627182Y-96948D01*
X625436Y-96365D01*
G01X685027Y-51365D02*
X690486Y-68865D01*
X695945Y-51365D01*
G01X712353Y-68865D02*
X703619D01*
Y-51365D01*
X712353D01*
G01X708859Y-59823D02*
X703619D01*
G01X721119Y-68865D02*
Y-51365D01*
X726578D01*
X728324Y-52240D01*
X729416Y-53407D01*
X729853Y-55740D01*
X729416Y-58074D01*
X728106Y-59532D01*
X726578Y-60407D01*
X721119D01*
G01X726578D02*
X729853Y-68865D01*
G01X742986Y-69448D02*
X742549Y-69157D01*
Y-68573D01*
X742986Y-68282D01*
X743423Y-68573D01*
Y-69157D01*
X742986Y-69448D01*
G01X707986Y-113865D02*
Y-96365D01*
X705366Y-99865D01*
G01Y-113865D02*
X710606D01*
G01X727232Y-104532D02*
X728106Y-103657D01*
X728761Y-102199D01*
X729198Y-100156D01*
X728761Y-98407D01*
X727888Y-97240D01*
X726359Y-96365D01*
X720464D01*
Y-113865D01*
X727669D01*
X729198Y-112699D01*
X730071Y-110948D01*
X730508Y-108907D01*
X730071Y-106865D01*
X728761Y-105115D01*
X727232Y-104532D01*
X720464D01*
G01X818569Y-96365D02*
Y-113865D01*
X827303D01*
G01X836288Y-106574D02*
X837816Y-104532D01*
X839126Y-103365D01*
X840873Y-102782D01*
X842401Y-103365D01*
X843493Y-104532D01*
X844366Y-106282D01*
X844584Y-108323D01*
X844366Y-110074D01*
X843493Y-111824D01*
X842182Y-113282D01*
X840654Y-113865D01*
X838908Y-113282D01*
X837379Y-111532D01*
X836506Y-108907D01*
X836288Y-105990D01*
X836724Y-102199D01*
X837379Y-100156D01*
X838471Y-98115D01*
X839999Y-96657D01*
X841528Y-96365D01*
X843056Y-96948D01*
X844148Y-98407D01*
G01X852477Y-96365D02*
X857936Y-113865D01*
X863395Y-96365D01*
G01X880239Y-97824D02*
X878929Y-96948D01*
X877401Y-96365D01*
X875654D01*
X873689Y-97240D01*
X872161Y-98698D01*
X871069Y-100449D01*
X870196Y-103365D01*
X869977Y-105990D01*
X870414Y-108615D01*
X871069Y-110365D01*
X872379Y-112115D01*
X873908Y-113282D01*
X875436Y-113865D01*
X876964D01*
X878493Y-113282D01*
X879803Y-112407D01*
X880895Y-111241D01*
G01X897739Y-97824D02*
X896429Y-96948D01*
X894901Y-96365D01*
X893154D01*
X891189Y-97240D01*
X889661Y-98698D01*
X888569Y-100449D01*
X887696Y-103365D01*
X887477Y-105990D01*
X887914Y-108615D01*
X888569Y-110365D01*
X889879Y-112115D01*
X891408Y-113282D01*
X892936Y-113865D01*
X894464D01*
X895993Y-113282D01*
X897303Y-112407D01*
X898395Y-111241D01*
G01X818569Y-51365D02*
Y-68865D01*
X827303D01*
G01X844366D02*
Y-57199D01*
G01Y-59240D02*
X843493Y-58074D01*
X842182Y-57490D01*
X840654Y-57199D01*
X839126Y-57782D01*
X837816Y-58948D01*
X836942Y-60698D01*
X836506Y-63032D01*
X836942Y-65365D01*
X837816Y-67115D01*
X839126Y-68282D01*
X840654Y-68865D01*
X842182Y-68573D01*
X843493Y-67699D01*
X844366Y-66532D01*
G01X853351Y-74115D02*
X854661Y-74698D01*
X856408Y-74115D01*
X857499Y-72949D01*
X858373Y-71490D01*
X859682Y-66824D01*
X862521Y-57199D01*
G01X855534D02*
X859682Y-66824D01*
G01X872161Y-60990D02*
X879148D01*
X878493Y-58948D01*
X877401Y-57782D01*
X875873Y-57199D01*
X874344Y-57490D01*
X873034Y-58365D01*
X872161Y-60407D01*
X871724Y-62157D01*
Y-63907D01*
X872161Y-65657D01*
X873253Y-67407D01*
X874563Y-68573D01*
X876091Y-68865D01*
X877619Y-68282D01*
X879148Y-66532D01*
G01X889879Y-68865D02*
Y-57199D01*
G01Y-59532D02*
X890971Y-58365D01*
X892063Y-57490D01*
X893591Y-57199D01*
X894682Y-57490D01*
X895993Y-58365D01*
G01X943619Y-110365D02*
X944711Y-112115D01*
X946021Y-113282D01*
X947549Y-113865D01*
X949296Y-113282D01*
X950606Y-112115D01*
X951916Y-110365D01*
X952353Y-108032D01*
Y-96365D01*
G01X965486Y-113865D02*
X963739Y-113573D01*
X962211Y-112407D01*
X960901Y-110657D01*
X960027Y-108615D01*
X959591Y-106282D01*
Y-103948D01*
X960027Y-101615D01*
X960901Y-99573D01*
X962211Y-97824D01*
X963739Y-96657D01*
X965486Y-96365D01*
X967232Y-96657D01*
X968761Y-97824D01*
X970071Y-99573D01*
X970945Y-101615D01*
X971381Y-103948D01*
Y-106282D01*
X970945Y-108615D01*
X970071Y-110657D01*
X968761Y-112407D01*
X967232Y-113573D01*
X965486Y-113865D01*
G01X978401Y-111532D02*
X980148Y-112990D01*
X982113Y-113865D01*
X983859D01*
X985606Y-112990D01*
X986916Y-111532D01*
X987571Y-109490D01*
X987134Y-107449D01*
X986043Y-105698D01*
X984078Y-104532D01*
X981458Y-103948D01*
X979929Y-102782D01*
X979274Y-100740D01*
X979711Y-98698D01*
X980803Y-97240D01*
X982331Y-96365D01*
X983859D01*
X985388Y-96948D01*
X986698Y-98407D01*
G01X1004853Y-113865D02*
X996119D01*
Y-96365D01*
X1004853D01*
G01X1001359Y-104823D02*
X996119D01*
G01X1013619Y-113865D02*
Y-96365D01*
X1018859D01*
X1020606Y-97240D01*
X1021916Y-99282D01*
X1022353Y-101615D01*
X1021916Y-103948D01*
X1020824Y-105698D01*
X1018859Y-106574D01*
X1013619D01*
G01X1030901Y-113865D02*
Y-96365D01*
G01X1040071D02*
Y-113865D01*
G01Y-105115D02*
X1030901D01*
G01X1066119Y-96365D02*
Y-113865D01*
X1074853D01*
G01X1082527D02*
X1087986Y-96365D01*
X1093445Y-113865D01*
G01X1091479Y-107740D02*
X1084492D01*
G01X1100683Y-96365D02*
Y-108907D01*
X1101556Y-111532D01*
X1103303Y-113282D01*
X1105486Y-113865D01*
X1107669Y-113282D01*
X1109416Y-111532D01*
X1110289Y-108907D01*
Y-96365D01*
G01X960683Y-68865D02*
Y-51365D01*
X965049D01*
X966796Y-52240D01*
X968106Y-53407D01*
X969198Y-55156D01*
X970071Y-57199D01*
X970289Y-60115D01*
X970071Y-63032D01*
X969198Y-65074D01*
X968106Y-66824D01*
X966796Y-67990D01*
X965049Y-68865D01*
X960683D01*
G01X979711Y-60990D02*
X986698D01*
X986043Y-58948D01*
X984951Y-57782D01*
X983423Y-57199D01*
X981894Y-57490D01*
X980584Y-58365D01*
X979711Y-60407D01*
X979274Y-62157D01*
Y-63907D01*
X979711Y-65657D01*
X980803Y-67407D01*
X982113Y-68573D01*
X983641Y-68865D01*
X985169Y-68282D01*
X986698Y-66532D01*
G01X997211Y-66824D02*
X998303Y-67990D01*
X999831Y-68865D01*
X1001141D01*
X1002451Y-68282D01*
X1003324Y-67407D01*
X1003761Y-66241D01*
X1003543Y-64490D01*
X1002669Y-63615D01*
X998739Y-61865D01*
X997866Y-59823D01*
X998303Y-58365D01*
X999176Y-57490D01*
X1000486Y-57199D01*
X1001796Y-57490D01*
X1003106Y-58365D01*
G01X1017986Y-57199D02*
Y-68865D01*
G01Y-52532D02*
X1017549Y-52240D01*
Y-51657D01*
X1017986Y-51365D01*
X1018423Y-51657D01*
Y-52240D01*
X1017986Y-52532D01*
G01X1032429Y-73240D02*
X1033958Y-74407D01*
X1035704Y-74698D01*
X1037232Y-74407D01*
X1038543Y-72949D01*
X1039416Y-70907D01*
Y-57199D01*
G01Y-59532D02*
X1038543Y-58365D01*
X1037232Y-57490D01*
X1035704Y-57199D01*
X1033958Y-57782D01*
X1032866Y-58948D01*
X1031992Y-60990D01*
X1031556Y-63032D01*
X1031774Y-64782D01*
X1032648Y-66824D01*
X1033958Y-68282D01*
X1035704Y-68865D01*
X1037014Y-68573D01*
X1038543Y-67407D01*
X1039416Y-66241D01*
G01X1049274Y-68865D02*
Y-57199D01*
G01Y-60115D02*
X1050148Y-58657D01*
X1051458Y-57490D01*
X1053204Y-57199D01*
X1054732Y-57490D01*
X1056043Y-58657D01*
X1056698Y-60698D01*
Y-68865D01*
G01X1067211Y-60990D02*
X1074198D01*
X1073543Y-58948D01*
X1072451Y-57782D01*
X1070923Y-57199D01*
X1069394Y-57490D01*
X1068084Y-58365D01*
X1067211Y-60407D01*
X1066774Y-62157D01*
Y-63907D01*
X1067211Y-65657D01*
X1068303Y-67407D01*
X1069613Y-68573D01*
X1071141Y-68865D01*
X1072669Y-68282D01*
X1074198Y-66532D01*
G01X1084929Y-68865D02*
Y-57199D01*
G01Y-59532D02*
X1086021Y-58365D01*
X1087113Y-57490D01*
X1088641Y-57199D01*
X1089732Y-57490D01*
X1091043Y-58365D01*
G01X1131686Y-113865D02*
Y-96365D01*
X1129066Y-99865D01*
G01Y-113865D02*
X1134306D01*
G01X1149186D02*
Y-96365D01*
X1146566Y-99865D01*
G01Y-113865D02*
X1151806D01*
G01X1162756Y-114448D02*
X1170616Y-96365D01*
G01X1184186Y-113865D02*
Y-96365D01*
X1181566Y-99865D01*
G01Y-113865D02*
X1186806D01*
G01X1196883Y-110365D02*
X1198192Y-112407D01*
X1199939Y-113573D01*
X1201904Y-113865D01*
X1203651Y-113573D01*
X1205398Y-112115D01*
X1206489Y-110365D01*
X1206708Y-108615D01*
X1206271Y-106574D01*
X1204743Y-105115D01*
X1203214Y-104532D01*
X1201249D01*
G01X1203214D02*
X1204524Y-103657D01*
X1205616Y-102199D01*
X1206053Y-100449D01*
X1205616Y-98698D01*
X1204524Y-97240D01*
X1202559Y-96365D01*
X1200594Y-96657D01*
X1198629Y-97824D01*
G01X1215256Y-114448D02*
X1223116Y-96365D01*
G01X1232538Y-99282D02*
X1233848Y-97532D01*
X1235376Y-96657D01*
X1237123Y-96365D01*
X1239306Y-96948D01*
X1240834Y-98407D01*
X1241271Y-100156D01*
X1241053Y-101907D01*
X1240179Y-103365D01*
X1235813Y-106282D01*
X1233848Y-108323D01*
X1232538Y-111241D01*
X1232101Y-113865D01*
X1241271D01*
G01X1254186Y-96365D02*
X1252439Y-96948D01*
X1251129Y-98407D01*
X1250256Y-100156D01*
X1249601Y-102490D01*
X1249383Y-105115D01*
X1249601Y-107740D01*
X1250256Y-110074D01*
X1251129Y-111824D01*
X1252439Y-113282D01*
X1254186Y-113865D01*
X1255932Y-113282D01*
X1257243Y-111824D01*
X1258116Y-110074D01*
X1258771Y-107740D01*
X1258989Y-105115D01*
X1258771Y-102490D01*
X1258116Y-100156D01*
X1257243Y-98407D01*
X1255932Y-96948D01*
X1254186Y-96365D01*
G01X1271686Y-113865D02*
Y-96365D01*
X1269066Y-99865D01*
G01Y-113865D02*
X1274306D01*
G01X1291806D02*
Y-96365D01*
X1283727Y-108907D01*
X1294645D01*
G01X1179383Y-68865D02*
Y-51365D01*
X1183749D01*
X1185496Y-52240D01*
X1186806Y-53407D01*
X1187898Y-55156D01*
X1188771Y-57199D01*
X1188989Y-60115D01*
X1188771Y-63032D01*
X1187898Y-65074D01*
X1186806Y-66824D01*
X1185496Y-67990D01*
X1183749Y-68865D01*
X1179383D01*
G01X1205616D02*
Y-57199D01*
G01Y-59240D02*
X1204743Y-58074D01*
X1203432Y-57490D01*
X1201904Y-57199D01*
X1200376Y-57782D01*
X1199066Y-58948D01*
X1198192Y-60698D01*
X1197756Y-63032D01*
X1198192Y-65365D01*
X1199066Y-67115D01*
X1200376Y-68282D01*
X1201904Y-68865D01*
X1203432Y-68573D01*
X1204743Y-67699D01*
X1205616Y-66532D01*
G01X1219186Y-51365D02*
Y-68865D01*
G01X1216129Y-57199D02*
X1222243D01*
G01X1233411Y-60990D02*
X1240398D01*
X1239743Y-58948D01*
X1238651Y-57782D01*
X1237123Y-57199D01*
X1235594Y-57490D01*
X1234284Y-58365D01*
X1233411Y-60407D01*
X1232974Y-62157D01*
Y-63907D01*
X1233411Y-65657D01*
X1234503Y-67407D01*
X1235813Y-68573D01*
X1237341Y-68865D01*
X1238869Y-68282D01*
X1240398Y-66532D01*
M02*
